(kicad_sch (version 20211123) (generator eeschema)

  (paper "A3")

  (title_block
    (title "SA800U (Snapdragon 845) Baseboard")
    (date "2023-10-19")
    (rev "1.0.3")
    (company "Antmicro Ltd.")
    (comment 1 "www.antmicro.com")
  )

  (junction (at 69.85 177.165) (diameter 0) (color 0 0 0 0)
  )
  (junction (at 168.275 267.335) (diameter 0) (color 0 0 0 0)
  )
  (junction (at 168.275 257.175) (diameter 0) (color 0 0 0 0)
  )
  (junction (at 315.595 187.96) (diameter 0) (color 0 0 0 0)
  )
  (junction (at 130.175 99.695) (diameter 0) (color 0 0 0 0)
  )
  (junction (at 107.315 24.765) (diameter 0) (color 0 0 0 0)
  )
  (junction (at 358.14 31.115) (diameter 0) (color 0 0 0 0)
  )
  (junction (at 119.38 81.28) (diameter 0) (color 0 0 0 0)
  )
  (junction (at 144.145 59.69) (diameter 0) (color 0 0 0 0)
  )
  (junction (at 273.685 170.18) (diameter 0) (color 0 0 0 0)
  )
  (junction (at 175.26 24.765) (diameter 0) (color 0 0 0 0)
  )
  (junction (at 133.985 59.69) (diameter 0) (color 0 0 0 0)
  )
  (junction (at 24.765 55.245) (diameter 0) (color 0 0 0 0)
  )
  (junction (at 107.315 34.925) (diameter 0) (color 0 0 0 0)
  )
  (junction (at 181.356 246.38) (diameter 0) (color 0 0 0 0)
  )
  (junction (at 117.475 34.925) (diameter 0) (color 0 0 0 0)
  )
  (junction (at 113.665 49.53) (diameter 0) (color 0 0 0 0)
  )
  (junction (at 288.925 162.56) (diameter 0) (color 0 0 0 0)
  )
  (junction (at 315.595 201.93) (diameter 0) (color 0 0 0 0)
  )
  (junction (at 83.185 179.705) (diameter 0) (color 0 0 0 0)
  )
  (junction (at 235.585 187.96) (diameter 0) (color 0 0 0 0)
  )
  (junction (at 208.915 24.765) (diameter 0) (color 0 0 0 0)
  )
  (junction (at 97.155 24.765) (diameter 0) (color 0 0 0 0)
  )
  (junction (at 271.78 227.33) (diameter 0) (color 0 0 0 0)
  )
  (junction (at 360.045 201.93) (diameter 0) (color 0 0 0 0)
  )
  (junction (at 43.18 131.445) (diameter 0) (color 0 0 0 0)
  )
  (junction (at 316.23 237.49) (diameter 0) (color 0 0 0 0)
  )
  (junction (at 281.305 149.86) (diameter 0) (color 0 0 0 0)
  )
  (junction (at 337.82 38.735) (diameter 0) (color 0 0 0 0)
  )
  (junction (at 333.375 180.34) (diameter 0) (color 0 0 0 0)
  )
  (junction (at 69.85 184.785) (diameter 0) (color 0 0 0 0)
  )
  (junction (at 92.71 247.015) (diameter 0) (color 0 0 0 0)
  )
  (junction (at 167.005 113.665) (diameter 0) (color 0 0 0 0)
  )
  (junction (at 297.815 56.515) (diameter 0) (color 0 0 0 0)
  )
  (junction (at 58.42 109.855) (diameter 0) (color 0 0 0 0)
  )
  (junction (at 93.345 49.53) (diameter 0) (color 0 0 0 0)
  )
  (junction (at 324.485 185.42) (diameter 0) (color 0 0 0 0)
  )
  (junction (at 182.245 267.335) (diameter 0) (color 0 0 0 0)
  )
  (junction (at 47.625 37.465) (diameter 0) (color 0 0 0 0)
  )
  (junction (at 351.155 201.93) (diameter 0) (color 0 0 0 0)
  )
  (junction (at 360.68 26.035) (diameter 0) (color 0 0 0 0)
  )
  (junction (at 333.375 201.93) (diameter 0) (color 0 0 0 0)
  )
  (junction (at 168.275 246.38) (diameter 0) (color 0 0 0 0)
  )
  (junction (at 130.175 114.935) (diameter 0) (color 0 0 0 0)
  )
  (junction (at 351.155 172.72) (diameter 0) (color 0 0 0 0)
  )
  (junction (at 258.445 177.8) (diameter 0) (color 0 0 0 0)
  )
  (junction (at 185.42 34.925) (diameter 0) (color 0 0 0 0)
  )
  (junction (at 316.23 227.33) (diameter 0) (color 0 0 0 0)
  )
  (junction (at 342.265 201.93) (diameter 0) (color 0 0 0 0)
  )
  (junction (at 361.95 201.93) (diameter 0) (color 0 0 0 0)
  )
  (junction (at 175.26 34.925) (diameter 0) (color 0 0 0 0)
  )
  (junction (at 226.695 257.175) (diameter 0) (color 0 0 0 0)
  )
  (junction (at 403.352 64.135) (diameter 0) (color 0 0 0 0)
  )
  (junction (at 47.625 61.595) (diameter 0) (color 0 0 0 0)
  )
  (junction (at 91.821 209.042) (diameter 0) (color 0 0 0 0)
  )
  (junction (at 41.91 198.755) (diameter 0) (color 0 0 0 0)
  )
  (junction (at 167.005 127.635) (diameter 0) (color 0 0 0 0)
  )
  (junction (at 272.415 90.17) (diameter 0) (color 0 0 0 0)
  )
  (junction (at 250.825 149.86) (diameter 0) (color 0 0 0 0)
  )
  (junction (at 24.765 31.115) (diameter 0) (color 0 0 0 0)
  )
  (junction (at 363.22 23.495) (diameter 0) (color 0 0 0 0)
  )
  (junction (at 160.401 155.575) (diameter 0) (color 0 0 0 0)
  )
  (junction (at 335.28 41.275) (diameter 0) (color 0 0 0 0)
  )
  (junction (at 156.845 81.28) (diameter 0) (color 0 0 0 0)
  )
  (junction (at 292.735 61.595) (diameter 0) (color 0 0 0 0)
  )
  (junction (at 355.6 33.655) (diameter 0) (color 0 0 0 0)
  )
  (junction (at 318.77 227.33) (diameter 0) (color 0 0 0 0)
  )
  (junction (at 47.625 69.215) (diameter 0) (color 0 0 0 0)
  )
  (junction (at 339.725 227.33) (diameter 0) (color 0 0 0 0)
  )
  (junction (at 273.685 149.86) (diameter 0) (color 0 0 0 0)
  )
  (junction (at 280.67 234.95) (diameter 0) (color 0 0 0 0)
  )
  (junction (at 266.065 149.86) (diameter 0) (color 0 0 0 0)
  )
  (junction (at 384.81 185.42) (diameter 0) (color 0 0 0 0)
  )
  (junction (at 130.175 108.585) (diameter 0) (color 0 0 0 0)
  )
  (junction (at 272.415 74.295) (diameter 0) (color 0 0 0 0)
  )
  (junction (at 117.475 24.765) (diameter 0) (color 0 0 0 0)
  )
  (junction (at 216.535 235.585) (diameter 0) (color 0 0 0 0)
  )
  (junction (at 403.352 71.755) (diameter 0) (color 0 0 0 0)
  )
  (junction (at 403.352 66.675) (diameter 0) (color 0 0 0 0)
  )
  (junction (at 160.655 130.175) (diameter 0) (color 0 0 0 0)
  )
  (junction (at 342.265 177.8) (diameter 0) (color 0 0 0 0)
  )
  (junction (at 109.22 81.28) (diameter 0) (color 0 0 0 0)
  )
  (junction (at 258.445 149.86) (diameter 0) (color 0 0 0 0)
  )
  (junction (at 154.94 24.765) (diameter 0) (color 0 0 0 0)
  )
  (junction (at 243.205 185.42) (diameter 0) (color 0 0 0 0)
  )
  (junction (at 174.625 130.175) (diameter 0) (color 0 0 0 0)
  )
  (junction (at 271.78 237.49) (diameter 0) (color 0 0 0 0)
  )
  (junction (at 47.625 45.085) (diameter 0) (color 0 0 0 0)
  )
  (junction (at 47.625 55.245) (diameter 0) (color 0 0 0 0)
  )
  (junction (at 250.825 180.34) (diameter 0) (color 0 0 0 0)
  )
  (junction (at 66.675 122.555) (diameter 0) (color 0 0 0 0)
  )
  (junction (at 330.2 48.895) (diameter 0) (color 0 0 0 0)
  )
  (junction (at 318.77 240.03) (diameter 0) (color 0 0 0 0)
  )
  (junction (at 219.075 34.925) (diameter 0) (color 0 0 0 0)
  )
  (junction (at 94.615 102.235) (diameter 0) (color 0 0 0 0)
  )
  (junction (at 165.1 24.765) (diameter 0) (color 0 0 0 0)
  )
  (junction (at 269.24 240.03) (diameter 0) (color 0 0 0 0)
  )
  (junction (at 94.615 111.125) (diameter 0) (color 0 0 0 0)
  )
  (junction (at 332.74 46.355) (diameter 0) (color 0 0 0 0)
  )
  (junction (at 144.145 49.53) (diameter 0) (color 0 0 0 0)
  )
  (junction (at 248.285 227.33) (diameter 0) (color 0 0 0 0)
  )
  (junction (at 47.625 31.115) (diameter 0) (color 0 0 0 0)
  )
  (junction (at 165.1 34.925) (diameter 0) (color 0 0 0 0)
  )
  (junction (at 269.24 227.33) (diameter 0) (color 0 0 0 0)
  )
  (junction (at 94.615 99.695) (diameter 0) (color 0 0 0 0)
  )
  (junction (at 403.352 74.295) (diameter 0) (color 0 0 0 0)
  )
  (junction (at 154.94 127.635) (diameter 0) (color 0 0 0 0)
  )
  (junction (at 24.765 61.595) (diameter 0) (color 0 0 0 0)
  )
  (junction (at 113.665 59.69) (diameter 0) (color 0 0 0 0)
  )
  (junction (at 368.935 165.1) (diameter 0) (color 0 0 0 0)
  )
  (junction (at 266.065 172.72) (diameter 0) (color 0 0 0 0)
  )
  (junction (at 103.505 49.53) (diameter 0) (color 0 0 0 0)
  )
  (junction (at 130.175 102.235) (diameter 0) (color 0 0 0 0)
  )
  (junction (at 43.18 109.855) (diameter 0) (color 0 0 0 0)
  )
  (junction (at 133.985 49.53) (diameter 0) (color 0 0 0 0)
  )
  (junction (at 103.505 59.69) (diameter 0) (color 0 0 0 0)
  )
  (junction (at 58.42 126.365) (diameter 0) (color 0 0 0 0)
  )
  (junction (at 99.06 71.12) (diameter 0) (color 0 0 0 0)
  )
  (junction (at 324.485 201.93) (diameter 0) (color 0 0 0 0)
  )
  (junction (at 168.275 236.22) (diameter 0) (color 0 0 0 0)
  )
  (junction (at 368.935 201.93) (diameter 0) (color 0 0 0 0)
  )
  (junction (at 290.195 66.675) (diameter 0) (color 0 0 0 0)
  )
  (junction (at 127.635 34.925) (diameter 0) (color 0 0 0 0)
  )
  (junction (at 88.265 182.245) (diameter 0) (color 0 0 0 0)
  )
  (junction (at 235.585 149.86) (diameter 0) (color 0 0 0 0)
  )
  (junction (at 123.825 59.69) (diameter 0) (color 0 0 0 0)
  )
  (junction (at 342.265 217.297) (diameter 0) (color 0 0 0 0)
  )
  (junction (at 146.685 71.12) (diameter 0) (color 0 0 0 0)
  )
  (junction (at 243.205 149.86) (diameter 0) (color 0 0 0 0)
  )
  (junction (at 50.8 128.905) (diameter 0) (color 0 0 0 0)
  )
  (junction (at 185.42 267.335) (diameter 0) (color 0 0 0 0)
  )
  (junction (at 280.035 66.675) (diameter 0) (color 0 0 0 0)
  )
  (junction (at 384.81 215.265) (diameter 0) (color 0 0 0 0)
  )
  (junction (at 360.045 170.18) (diameter 0) (color 0 0 0 0)
  )
  (junction (at 295.275 53.975) (diameter 0) (color 0 0 0 0)
  )
  (junction (at 123.825 49.53) (diameter 0) (color 0 0 0 0)
  )
  (junction (at 154.305 59.69) (diameter 0) (color 0 0 0 0)
  )
  (junction (at 211.963 257.175) (diameter 0) (color 0 0 0 0)
  )
  (junction (at 389.89 187.96) (diameter 0) (color 0 0 0 0)
  )
  (junction (at 50.8 109.855) (diameter 0) (color 0 0 0 0)
  )
  (junction (at 24.765 37.465) (diameter 0) (color 0 0 0 0)
  )
  (junction (at 377.825 162.56) (diameter 0) (color 0 0 0 0)
  )
  (junction (at 109.22 71.12) (diameter 0) (color 0 0 0 0)
  )
  (junction (at 130.175 106.045) (diameter 0) (color 0 0 0 0)
  )
  (junction (at 403.352 69.215) (diameter 0) (color 0 0 0 0)
  )
  (junction (at 281.305 165.1) (diameter 0) (color 0 0 0 0)
  )

  (no_connect (at 128.905 163.195))
  (no_connect (at 128.905 170.815))
  (no_connect (at 128.905 188.595))
  (no_connect (at 128.905 180.975))
  (no_connect (at 128.905 168.275))
  (no_connect (at 128.905 178.435))
  (no_connect (at 128.905 165.735))
  (no_connect (at 128.905 191.135))
  (no_connect (at 375.92 69.215))
  (no_connect (at 128.905 186.055))
  (no_connect (at 128.905 196.215))
  (no_connect (at 128.905 160.655))
  (no_connect (at 128.905 175.895))
  (no_connect (at 128.905 198.755))
  (no_connect (at 128.905 183.515))
  (no_connect (at 128.905 193.675))

  (wire (pts (xy 300.101 180.34) (xy 333.375 180.34))
    (stroke (width 0) (type default) (color 0 0 0 0))
  )
  (wire (pts (xy 316.23 242.57) (xy 316.23 237.49))
    (stroke (width 0) (type default) (color 0 0 0 0))
  )
  (wire (pts (xy 269.24 227.33) (xy 271.78 227.33))
    (stroke (width 0) (type default) (color 0 0 0 0))
  )
  (wire (pts (xy 130.175 99.695) (xy 149.86 99.695))
    (stroke (width 0) (type default) (color 0 0 0 0))
  )
  (wire (pts (xy 258.445 149.86) (xy 266.065 149.86))
    (stroke (width 0) (type default) (color 0 0 0 0))
  )
  (wire (pts (xy 304.165 23.495) (xy 304.165 22.225))
    (stroke (width 0) (type default) (color 0 0 0 0))
  )
  (wire (pts (xy 254.635 33.655) (xy 288.925 33.655))
    (stroke (width 0) (type default) (color 0 0 0 0))
  )
  (wire (pts (xy 128.905 114.935) (xy 130.175 114.935))
    (stroke (width 0) (type default) (color 0 0 0 0))
  )
  (wire (pts (xy 24.765 37.465) (xy 29.337 37.465))
    (stroke (width 0) (type default) (color 0 0 0 0))
  )
  (wire (pts (xy 146.685 71.12) (xy 156.845 71.12))
    (stroke (width 0) (type default) (color 0 0 0 0))
  )
  (wire (pts (xy 43.18 109.855) (xy 50.8 109.855))
    (stroke (width 0) (type default) (color 0 0 0 0))
  )
  (wire (pts (xy 273.685 170.18) (xy 298.196 170.18))
    (stroke (width 0) (type default) (color 0 0 0 0))
  )
  (wire (pts (xy 208.915 24.765) (xy 219.075 24.765))
    (stroke (width 0) (type default) (color 0 0 0 0))
  )
  (wire (pts (xy 321.945 78.74) (xy 321.945 90.17))
    (stroke (width 0) (type default) (color 0 0 0 0))
  )
  (wire (pts (xy 41.91 198.755) (xy 41.91 201.422))
    (stroke (width 0) (type default) (color 0 0 0 0))
  )
  (wire (pts (xy 168.275 257.175) (xy 167.005 257.175))
    (stroke (width 0) (type default) (color 0 0 0 0))
  )
  (wire (pts (xy 235.585 158.75) (xy 235.585 187.96))
    (stroke (width 0) (type default) (color 0 0 0 0))
  )
  (wire (pts (xy 160.655 126.365) (xy 160.655 130.175))
    (stroke (width 0) (type default) (color 0 0 0 0))
  )
  (wire (pts (xy 36.83 156.845) (xy 95.885 156.845))
    (stroke (width 0) (type default) (color 0 0 0 0))
  )
  (wire (pts (xy 41.91 206.502) (xy 41.91 206.375))
    (stroke (width 0) (type default) (color 0 0 0 0))
  )
  (wire (pts (xy 334.137 212.09) (xy 334.645 212.09))
    (stroke (width 0) (type default) (color 0 0 0 0))
  )
  (wire (pts (xy 107.315 24.765) (xy 107.315 27.305))
    (stroke (width 0) (type default) (color 0 0 0 0))
  )
  (wire (pts (xy 50.8 109.855) (xy 58.42 109.855))
    (stroke (width 0) (type default) (color 0 0 0 0))
  )
  (wire (pts (xy 342.265 215.9) (xy 342.265 217.297))
    (stroke (width 0) (type default) (color 0 0 0 0))
  )
  (wire (pts (xy 401.32 71.755) (xy 403.352 71.755))
    (stroke (width 0) (type default) (color 0 0 0 0))
  )
  (wire (pts (xy 281.305 149.86) (xy 288.925 149.86))
    (stroke (width 0) (type default) (color 0 0 0 0))
  )
  (wire (pts (xy 384.81 185.42) (xy 401.955 185.42))
    (stroke (width 0) (type default) (color 0 0 0 0))
  )
  (wire (pts (xy 146.685 81.28) (xy 146.685 78.74))
    (stroke (width 0) (type default) (color 0 0 0 0))
  )
  (wire (pts (xy 119.38 81.28) (xy 119.38 82.55))
    (stroke (width 0) (type default) (color 0 0 0 0))
  )
  (wire (pts (xy 24.13 126.365) (xy 58.42 126.365))
    (stroke (width 0) (type default) (color 0 0 0 0))
  )
  (wire (pts (xy 117.475 24.765) (xy 117.475 27.305))
    (stroke (width 0) (type default) (color 0 0 0 0))
  )
  (wire (pts (xy 128.905 99.695) (xy 130.175 99.695))
    (stroke (width 0) (type default) (color 0 0 0 0))
  )
  (wire (pts (xy 114.3 252.095) (xy 135.89 252.095))
    (stroke (width 0) (type default) (color 0 0 0 0))
  )
  (wire (pts (xy 250.825 180.34) (xy 295.021 180.34))
    (stroke (width 0) (type default) (color 0 0 0 0))
  )
  (wire (pts (xy 128.905 111.125) (xy 130.175 111.125))
    (stroke (width 0) (type default) (color 0 0 0 0))
  )
  (wire (pts (xy 333.375 191.77) (xy 333.375 180.34))
    (stroke (width 0) (type default) (color 0 0 0 0))
  )
  (wire (pts (xy 128.905 153.035) (xy 189.23 153.035))
    (stroke (width 0) (type default) (color 0 0 0 0))
  )
  (wire (pts (xy 175.26 24.765) (xy 185.42 24.765))
    (stroke (width 0) (type default) (color 0 0 0 0))
  )
  (wire (pts (xy 324.485 191.77) (xy 324.485 185.42))
    (stroke (width 0) (type default) (color 0 0 0 0))
  )
  (wire (pts (xy 168.275 243.078) (xy 168.275 246.38))
    (stroke (width 0) (type default) (color 0 0 0 0))
  )
  (wire (pts (xy 103.505 59.69) (xy 113.665 59.69))
    (stroke (width 0) (type default) (color 0 0 0 0))
  )
  (wire (pts (xy 129.54 234.95) (xy 129.54 238.76))
    (stroke (width 0) (type default) (color 0 0 0 0))
  )
  (wire (pts (xy 226.695 266.7) (xy 226.695 257.175))
    (stroke (width 0) (type default) (color 0 0 0 0))
  )
  (wire (pts (xy 304.165 41.275) (xy 335.28 41.275))
    (stroke (width 0) (type default) (color 0 0 0 0))
  )
  (wire (pts (xy 351.155 172.72) (xy 401.955 172.72))
    (stroke (width 0) (type default) (color 0 0 0 0))
  )
  (wire (pts (xy 304.165 242.57) (xy 305.435 242.57))
    (stroke (width 0) (type default) (color 0 0 0 0))
  )
  (wire (pts (xy 342.265 201.93) (xy 351.155 201.93))
    (stroke (width 0) (type default) (color 0 0 0 0))
  )
  (wire (pts (xy 133.985 59.69) (xy 144.145 59.69))
    (stroke (width 0) (type default) (color 0 0 0 0))
  )
  (wire (pts (xy 117.475 24.765) (xy 127.635 24.765))
    (stroke (width 0) (type default) (color 0 0 0 0))
  )
  (wire (pts (xy 128.27 231.775) (xy 134.62 231.775))
    (stroke (width 0) (type default) (color 0 0 0 0))
  )
  (wire (pts (xy 318.77 227.33) (xy 339.725 227.33))
    (stroke (width 0) (type default) (color 0 0 0 0))
  )
  (wire (pts (xy 272.415 74.295) (xy 375.92 74.295))
    (stroke (width 0) (type default) (color 0 0 0 0))
  )
  (wire (pts (xy 304.165 31.115) (xy 358.14 31.115))
    (stroke (width 0) (type default) (color 0 0 0 0))
  )
  (wire (pts (xy 272.415 90.17) (xy 280.035 90.17))
    (stroke (width 0) (type default) (color 0 0 0 0))
  )
  (wire (pts (xy 272.415 90.17) (xy 272.415 93.98))
    (stroke (width 0) (type default) (color 0 0 0 0))
  )
  (wire (pts (xy 292.735 61.595) (xy 375.92 61.595))
    (stroke (width 0) (type default) (color 0 0 0 0))
  )
  (wire (pts (xy 254.635 48.895) (xy 288.925 48.895))
    (stroke (width 0) (type default) (color 0 0 0 0))
  )
  (wire (pts (xy 154.305 57.15) (xy 154.305 59.69))
    (stroke (width 0) (type default) (color 0 0 0 0))
  )
  (wire (pts (xy 36.83 146.685) (xy 95.885 146.685))
    (stroke (width 0) (type default) (color 0 0 0 0))
  )
  (wire (pts (xy 128.905 122.555) (xy 149.86 122.555))
    (stroke (width 0) (type default) (color 0 0 0 0))
  )
  (wire (pts (xy 24.765 169.545) (xy 95.885 169.545))
    (stroke (width 0) (type default) (color 0 0 0 0))
  )
  (wire (pts (xy 144.145 59.69) (xy 154.305 59.69))
    (stroke (width 0) (type default) (color 0 0 0 0))
  )
  (wire (pts (xy 103.505 49.53) (xy 113.665 49.53))
    (stroke (width 0) (type default) (color 0 0 0 0))
  )
  (wire (pts (xy 181.356 236.22) (xy 182.626 236.22))
    (stroke (width 0) (type default) (color 0 0 0 0))
  )
  (wire (pts (xy 97.155 24.765) (xy 97.155 27.305))
    (stroke (width 0) (type default) (color 0 0 0 0))
  )
  (wire (pts (xy 34.417 61.595) (xy 47.625 61.595))
    (stroke (width 0) (type default) (color 0 0 0 0))
  )
  (wire (pts (xy 315.595 191.77) (xy 315.595 187.96))
    (stroke (width 0) (type default) (color 0 0 0 0))
  )
  (wire (pts (xy 117.475 34.925) (xy 107.315 34.925))
    (stroke (width 0) (type default) (color 0 0 0 0))
  )
  (wire (pts (xy 24.765 61.595) (xy 29.337 61.595))
    (stroke (width 0) (type default) (color 0 0 0 0))
  )
  (wire (pts (xy 94.615 106.045) (xy 94.615 102.235))
    (stroke (width 0) (type default) (color 0 0 0 0))
  )
  (wire (pts (xy 109.22 81.28) (xy 119.38 81.28))
    (stroke (width 0) (type default) (color 0 0 0 0))
  )
  (wire (pts (xy 273.685 149.86) (xy 281.305 149.86))
    (stroke (width 0) (type default) (color 0 0 0 0))
  )
  (wire (pts (xy 280.67 227.33) (xy 280.67 234.95))
    (stroke (width 0) (type default) (color 0 0 0 0))
  )
  (wire (pts (xy 36.83 159.385) (xy 95.885 159.385))
    (stroke (width 0) (type default) (color 0 0 0 0))
  )
  (wire (pts (xy 113.665 49.53) (xy 123.825 49.53))
    (stroke (width 0) (type default) (color 0 0 0 0))
  )
  (wire (pts (xy 180.975 267.335) (xy 182.245 267.335))
    (stroke (width 0) (type default) (color 0 0 0 0))
  )
  (wire (pts (xy 93.98 252.095) (xy 90.17 252.095))
    (stroke (width 0) (type default) (color 0 0 0 0))
  )
  (wire (pts (xy 281.305 165.1) (xy 295.021 165.1))
    (stroke (width 0) (type default) (color 0 0 0 0))
  )
  (wire (pts (xy 358.14 31.115) (xy 375.92 31.115))
    (stroke (width 0) (type default) (color 0 0 0 0))
  )
  (wire (pts (xy 243.205 158.75) (xy 243.205 185.42))
    (stroke (width 0) (type default) (color 0 0 0 0))
  )
  (wire (pts (xy 24.765 164.465) (xy 95.885 164.465))
    (stroke (width 0) (type default) (color 0 0 0 0))
  )
  (wire (pts (xy 160.401 155.575) (xy 160.401 158.115))
    (stroke (width 0) (type default) (color 0 0 0 0))
  )
  (wire (pts (xy 128.905 155.575) (xy 160.401 155.575))
    (stroke (width 0) (type default) (color 0 0 0 0))
  )
  (wire (pts (xy 304.165 33.655) (xy 304.165 34.925))
    (stroke (width 0) (type default) (color 0 0 0 0))
  )
  (wire (pts (xy 130.175 114.935) (xy 149.86 114.935))
    (stroke (width 0) (type default) (color 0 0 0 0))
  )
  (wire (pts (xy 303.276 162.56) (xy 377.825 162.56))
    (stroke (width 0) (type default) (color 0 0 0 0))
  )
  (wire (pts (xy 128.905 130.175) (xy 160.655 130.175))
    (stroke (width 0) (type default) (color 0 0 0 0))
  )
  (wire (pts (xy 128.905 108.585) (xy 130.175 108.585))
    (stroke (width 0) (type default) (color 0 0 0 0))
  )
  (wire (pts (xy 36.83 141.605) (xy 95.885 141.605))
    (stroke (width 0) (type default) (color 0 0 0 0))
  )
  (wire (pts (xy 208.915 34.925) (xy 208.915 32.385))
    (stroke (width 0) (type default) (color 0 0 0 0))
  )
  (wire (pts (xy 41.91 196.342) (xy 41.91 198.755))
    (stroke (width 0) (type default) (color 0 0 0 0))
  )
  (wire (pts (xy 181.356 243.078) (xy 181.356 246.38))
    (stroke (width 0) (type default) (color 0 0 0 0))
  )
  (wire (pts (xy 288.925 50.165) (xy 288.925 48.895))
    (stroke (width 0) (type default) (color 0 0 0 0))
  )
  (wire (pts (xy 128.905 142.875) (xy 189.23 142.875))
    (stroke (width 0) (type default) (color 0 0 0 0))
  )
  (wire (pts (xy 360.045 201.93) (xy 360.045 196.85))
    (stroke (width 0) (type default) (color 0 0 0 0))
  )
  (wire (pts (xy 107.315 32.385) (xy 107.315 34.925))
    (stroke (width 0) (type default) (color 0 0 0 0))
  )
  (wire (pts (xy 258.445 158.75) (xy 258.445 177.8))
    (stroke (width 0) (type default) (color 0 0 0 0))
  )
  (wire (pts (xy 288.925 29.845) (xy 288.925 31.115))
    (stroke (width 0) (type default) (color 0 0 0 0))
  )
  (wire (pts (xy 330.2 48.895) (xy 330.2 80.01))
    (stroke (width 0) (type default) (color 0 0 0 0))
  )
  (wire (pts (xy 248.285 227.33) (xy 269.24 227.33))
    (stroke (width 0) (type default) (color 0 0 0 0))
  )
  (wire (pts (xy 280.035 84.328) (xy 280.035 90.17))
    (stroke (width 0) (type default) (color 0 0 0 0))
  )
  (wire (pts (xy 113.665 59.69) (xy 123.825 59.69))
    (stroke (width 0) (type default) (color 0 0 0 0))
  )
  (wire (pts (xy 154.94 127.635) (xy 167.005 127.635))
    (stroke (width 0) (type default) (color 0 0 0 0))
  )
  (wire (pts (xy 360.045 191.77) (xy 360.045 170.18))
    (stroke (width 0) (type default) (color 0 0 0 0))
  )
  (wire (pts (xy 163.195 267.335) (xy 168.275 267.335))
    (stroke (width 0) (type default) (color 0 0 0 0))
  )
  (wire (pts (xy 217.17 165.1) (xy 281.305 165.1))
    (stroke (width 0) (type default) (color 0 0 0 0))
  )
  (wire (pts (xy 329.057 212.09) (xy 327.152 212.09))
    (stroke (width 0) (type default) (color 0 0 0 0))
  )
  (wire (pts (xy 254.635 26.035) (xy 288.925 26.035))
    (stroke (width 0) (type default) (color 0 0 0 0))
  )
  (wire (pts (xy 316.23 237.49) (xy 335.915 237.49))
    (stroke (width 0) (type default) (color 0 0 0 0))
  )
  (wire (pts (xy 315.595 201.93) (xy 324.485 201.93))
    (stroke (width 0) (type default) (color 0 0 0 0))
  )
  (wire (pts (xy 144.145 49.53) (xy 154.305 49.53))
    (stroke (width 0) (type default) (color 0 0 0 0))
  )
  (wire (pts (xy 76.835 182.245) (xy 88.265 182.245))
    (stroke (width 0) (type default) (color 0 0 0 0))
  )
  (wire (pts (xy 114.3 257.175) (xy 135.89 257.175))
    (stroke (width 0) (type default) (color 0 0 0 0))
  )
  (wire (pts (xy 330.2 48.895) (xy 375.92 48.895))
    (stroke (width 0) (type default) (color 0 0 0 0))
  )
  (wire (pts (xy 130.175 106.045) (xy 130.175 108.585))
    (stroke (width 0) (type default) (color 0 0 0 0))
  )
  (wire (pts (xy 266.065 172.72) (xy 295.021 172.72))
    (stroke (width 0) (type default) (color 0 0 0 0))
  )
  (wire (pts (xy 24.13 122.555) (xy 66.675 122.555))
    (stroke (width 0) (type default) (color 0 0 0 0))
  )
  (wire (pts (xy 292.735 61.595) (xy 292.735 93.98))
    (stroke (width 0) (type default) (color 0 0 0 0))
  )
  (wire (pts (xy 67.945 184.785) (xy 69.85 184.785))
    (stroke (width 0) (type default) (color 0 0 0 0))
  )
  (wire (pts (xy 133.985 49.53) (xy 133.985 52.07))
    (stroke (width 0) (type default) (color 0 0 0 0))
  )
  (wire (pts (xy 389.89 207.645) (xy 389.89 187.96))
    (stroke (width 0) (type default) (color 0 0 0 0))
  )
  (wire (pts (xy 300.101 187.96) (xy 315.595 187.96))
    (stroke (width 0) (type default) (color 0 0 0 0))
  )
  (wire (pts (xy 36.83 154.305) (xy 95.885 154.305))
    (stroke (width 0) (type default) (color 0 0 0 0))
  )
  (wire (pts (xy 128.905 140.335) (xy 189.23 140.335))
    (stroke (width 0) (type default) (color 0 0 0 0))
  )
  (wire (pts (xy 377.825 201.93) (xy 377.825 196.85))
    (stroke (width 0) (type default) (color 0 0 0 0))
  )
  (wire (pts (xy 24.765 37.465) (xy 24.765 45.085))
    (stroke (width 0) (type default) (color 0 0 0 0))
  )
  (wire (pts (xy 403.352 64.135) (xy 403.352 66.675))
    (stroke (width 0) (type default) (color 0 0 0 0))
  )
  (wire (pts (xy 59.055 177.165) (xy 69.85 177.165))
    (stroke (width 0) (type default) (color 0 0 0 0))
  )
  (wire (pts (xy 361.95 217.297) (xy 361.95 211.201))
    (stroke (width 0) (type default) (color 0 0 0 0))
  )
  (wire (pts (xy 363.22 23.495) (xy 375.92 23.495))
    (stroke (width 0) (type default) (color 0 0 0 0))
  )
  (wire (pts (xy 34.417 55.245) (xy 47.625 55.245))
    (stroke (width 0) (type default) (color 0 0 0 0))
  )
  (wire (pts (xy 99.06 81.28) (xy 99.06 78.74))
    (stroke (width 0) (type default) (color 0 0 0 0))
  )
  (wire (pts (xy 358.14 80.01) (xy 358.14 31.115))
    (stroke (width 0) (type default) (color 0 0 0 0))
  )
  (wire (pts (xy 127.635 24.765) (xy 127.635 27.305))
    (stroke (width 0) (type default) (color 0 0 0 0))
  )
  (wire (pts (xy 182.245 257.175) (xy 183.515 257.175))
    (stroke (width 0) (type default) (color 0 0 0 0))
  )
  (wire (pts (xy 78.105 49.53) (xy 93.345 49.53))
    (stroke (width 0) (type default) (color 0 0 0 0))
  )
  (wire (pts (xy 216.535 235.585) (xy 215.265 235.585))
    (stroke (width 0) (type default) (color 0 0 0 0))
  )
  (wire (pts (xy 271.78 235.077) (xy 271.78 237.49))
    (stroke (width 0) (type default) (color 0 0 0 0))
  )
  (wire (pts (xy 123.825 59.69) (xy 133.985 59.69))
    (stroke (width 0) (type default) (color 0 0 0 0))
  )
  (wire (pts (xy 90.17 257.175) (xy 93.98 257.175))
    (stroke (width 0) (type default) (color 0 0 0 0))
  )
  (wire (pts (xy 92.71 272.415) (xy 92.71 247.015))
    (stroke (width 0) (type default) (color 0 0 0 0))
  )
  (wire (pts (xy 401.32 69.215) (xy 403.352 69.215))
    (stroke (width 0) (type default) (color 0 0 0 0))
  )
  (wire (pts (xy 316.23 234.696) (xy 316.23 237.49))
    (stroke (width 0) (type default) (color 0 0 0 0))
  )
  (wire (pts (xy 189.865 24.765) (xy 208.915 24.765))
    (stroke (width 0) (type default) (color 0 0 0 0))
  )
  (wire (pts (xy 47.625 31.115) (xy 66.675 31.115))
    (stroke (width 0) (type default) (color 0 0 0 0))
  )
  (wire (pts (xy 304.165 38.735) (xy 337.82 38.735))
    (stroke (width 0) (type default) (color 0 0 0 0))
  )
  (wire (pts (xy 175.26 34.925) (xy 165.1 34.925))
    (stroke (width 0) (type default) (color 0 0 0 0))
  )
  (wire (pts (xy 281.305 149.86) (xy 281.305 153.67))
    (stroke (width 0) (type default) (color 0 0 0 0))
  )
  (wire (pts (xy 351.155 191.77) (xy 351.155 172.72))
    (stroke (width 0) (type default) (color 0 0 0 0))
  )
  (wire (pts (xy 58.42 116.205) (xy 58.42 126.365))
    (stroke (width 0) (type default) (color 0 0 0 0))
  )
  (wire (pts (xy 297.815 93.98) (xy 297.815 56.515))
    (stroke (width 0) (type default) (color 0 0 0 0))
  )
  (wire (pts (xy 271.78 229.997) (xy 271.78 227.33))
    (stroke (width 0) (type default) (color 0 0 0 0))
  )
  (wire (pts (xy 226.695 244.856) (xy 226.695 248.285))
    (stroke (width 0) (type default) (color 0 0 0 0))
  )
  (wire (pts (xy 318.77 242.57) (xy 318.77 240.03))
    (stroke (width 0) (type default) (color 0 0 0 0))
  )
  (wire (pts (xy 389.89 187.96) (xy 401.955 187.96))
    (stroke (width 0) (type default) (color 0 0 0 0))
  )
  (wire (pts (xy 79.375 71.12) (xy 99.06 71.12))
    (stroke (width 0) (type default) (color 0 0 0 0))
  )
  (wire (pts (xy 304.165 38.735) (xy 304.165 37.465))
    (stroke (width 0) (type default) (color 0 0 0 0))
  )
  (wire (pts (xy 315.595 187.96) (xy 389.89 187.96))
    (stroke (width 0) (type default) (color 0 0 0 0))
  )
  (wire (pts (xy 217.17 201.93) (xy 315.595 201.93))
    (stroke (width 0) (type default) (color 0 0 0 0))
  )
  (wire (pts (xy 226.695 253.365) (xy 226.695 257.175))
    (stroke (width 0) (type default) (color 0 0 0 0))
  )
  (wire (pts (xy 95.885 102.235) (xy 94.615 102.235))
    (stroke (width 0) (type default) (color 0 0 0 0))
  )
  (wire (pts (xy 307.34 227.33) (xy 316.23 227.33))
    (stroke (width 0) (type default) (color 0 0 0 0))
  )
  (wire (pts (xy 360.68 26.035) (xy 360.68 80.01))
    (stroke (width 0) (type default) (color 0 0 0 0))
  )
  (wire (pts (xy 113.665 57.15) (xy 113.665 59.69))
    (stroke (width 0) (type default) (color 0 0 0 0))
  )
  (wire (pts (xy 88.265 182.245) (xy 88.265 185.42))
    (stroke (width 0) (type default) (color 0 0 0 0))
  )
  (wire (pts (xy 304.165 46.355) (xy 304.165 45.085))
    (stroke (width 0) (type default) (color 0 0 0 0))
  )
  (wire (pts (xy 50.8 116.205) (xy 50.8 128.905))
    (stroke (width 0) (type default) (color 0 0 0 0))
  )
  (wire (pts (xy 83.185 179.705) (xy 95.885 179.705))
    (stroke (width 0) (type default) (color 0 0 0 0))
  )
  (wire (pts (xy 83.185 179.705) (xy 83.185 185.42))
    (stroke (width 0) (type default) (color 0 0 0 0))
  )
  (wire (pts (xy 144.145 59.69) (xy 144.145 57.15))
    (stroke (width 0) (type default) (color 0 0 0 0))
  )
  (wire (pts (xy 217.17 172.72) (xy 266.065 172.72))
    (stroke (width 0) (type default) (color 0 0 0 0))
  )
  (wire (pts (xy 219.075 34.925) (xy 208.915 34.925))
    (stroke (width 0) (type default) (color 0 0 0 0))
  )
  (wire (pts (xy 316.23 227.33) (xy 318.77 227.33))
    (stroke (width 0) (type default) (color 0 0 0 0))
  )
  (wire (pts (xy 126.365 71.12) (xy 146.685 71.12))
    (stroke (width 0) (type default) (color 0 0 0 0))
  )
  (wire (pts (xy 128.905 203.835) (xy 189.484 203.835))
    (stroke (width 0) (type default) (color 0 0 0 0))
  )
  (wire (pts (xy 156.845 81.28) (xy 156.845 82.55))
    (stroke (width 0) (type default) (color 0 0 0 0))
  )
  (wire (pts (xy 216.535 240.665) (xy 216.535 235.585))
    (stroke (width 0) (type default) (color 0 0 0 0))
  )
  (wire (pts (xy 95.885 201.295) (xy 91.821 201.295))
    (stroke (width 0) (type default) (color 0 0 0 0))
  )
  (wire (pts (xy 66.675 109.855) (xy 66.675 111.125))
    (stroke (width 0) (type default) (color 0 0 0 0))
  )
  (wire (pts (xy 384.81 215.265) (xy 389.89 215.265))
    (stroke (width 0) (type default) (color 0 0 0 0))
  )
  (wire (pts (xy 40.64 187.325) (xy 41.91 187.325))
    (stroke (width 0) (type default) (color 0 0 0 0))
  )
  (wire (pts (xy 269.24 229.997) (xy 269.24 227.33))
    (stroke (width 0) (type default) (color 0 0 0 0))
  )
  (wire (pts (xy 168.275 236.22) (xy 167.005 236.22))
    (stroke (width 0) (type default) (color 0 0 0 0))
  )
  (wire (pts (xy 133.985 57.15) (xy 133.985 59.69))
    (stroke (width 0) (type default) (color 0 0 0 0))
  )
  (wire (pts (xy 24.765 31.115) (xy 29.337 31.115))
    (stroke (width 0) (type default) (color 0 0 0 0))
  )
  (wire (pts (xy 225.425 257.175) (xy 226.695 257.175))
    (stroke (width 0) (type default) (color 0 0 0 0))
  )
  (wire (pts (xy 351.155 201.93) (xy 360.045 201.93))
    (stroke (width 0) (type default) (color 0 0 0 0))
  )
  (wire (pts (xy 128.905 102.235) (xy 130.175 102.235))
    (stroke (width 0) (type default) (color 0 0 0 0))
  )
  (wire (pts (xy 41.91 198.755) (xy 95.885 198.755))
    (stroke (width 0) (type default) (color 0 0 0 0))
  )
  (wire (pts (xy 154.94 34.925) (xy 154.94 32.385))
    (stroke (width 0) (type default) (color 0 0 0 0))
  )
  (wire (pts (xy 34.417 31.115) (xy 47.625 31.115))
    (stroke (width 0) (type default) (color 0 0 0 0))
  )
  (wire (pts (xy 273.685 149.86) (xy 273.685 153.67))
    (stroke (width 0) (type default) (color 0 0 0 0))
  )
  (wire (pts (xy 113.665 49.53) (xy 113.665 52.07))
    (stroke (width 0) (type default) (color 0 0 0 0))
  )
  (wire (pts (xy 69.85 184.785) (xy 76.835 184.785))
    (stroke (width 0) (type default) (color 0 0 0 0))
  )
  (wire (pts (xy 156.845 78.74) (xy 156.845 81.28))
    (stroke (width 0) (type default) (color 0 0 0 0))
  )
  (wire (pts (xy 217.17 162.56) (xy 288.925 162.56))
    (stroke (width 0) (type default) (color 0 0 0 0))
  )
  (wire (pts (xy 304.165 240.03) (xy 318.77 240.03))
    (stroke (width 0) (type default) (color 0 0 0 0))
  )
  (wire (pts (xy 128.905 137.795) (xy 189.23 137.795))
    (stroke (width 0) (type default) (color 0 0 0 0))
  )
  (wire (pts (xy 172.085 236.22) (xy 172.085 238.76))
    (stroke (width 0) (type default) (color 0 0 0 0))
  )
  (wire (pts (xy 254.635 46.355) (xy 288.925 46.355))
    (stroke (width 0) (type default) (color 0 0 0 0))
  )
  (wire (pts (xy 165.1 24.765) (xy 165.1 27.305))
    (stroke (width 0) (type default) (color 0 0 0 0))
  )
  (wire (pts (xy 154.94 126.365) (xy 154.94 127.635))
    (stroke (width 0) (type default) (color 0 0 0 0))
  )
  (wire (pts (xy 300.101 165.1) (xy 368.935 165.1))
    (stroke (width 0) (type default) (color 0 0 0 0))
  )
  (wire (pts (xy 40.64 109.855) (xy 43.18 109.855))
    (stroke (width 0) (type default) (color 0 0 0 0))
  )
  (wire (pts (xy 368.935 165.1) (xy 401.955 165.1))
    (stroke (width 0) (type default) (color 0 0 0 0))
  )
  (wire (pts (xy 123.825 49.53) (xy 123.825 52.07))
    (stroke (width 0) (type default) (color 0 0 0 0))
  )
  (wire (pts (xy 66.675 116.205) (xy 66.675 122.555))
    (stroke (width 0) (type default) (color 0 0 0 0))
  )
  (wire (pts (xy 217.17 180.34) (xy 250.825 180.34))
    (stroke (width 0) (type default) (color 0 0 0 0))
  )
  (wire (pts (xy 361.95 201.93) (xy 368.935 201.93))
    (stroke (width 0) (type default) (color 0 0 0 0))
  )
  (wire (pts (xy 280.035 66.675) (xy 280.035 79.248))
    (stroke (width 0) (type default) (color 0 0 0 0))
  )
  (wire (pts (xy 130.175 102.235) (xy 130.175 99.695))
    (stroke (width 0) (type default) (color 0 0 0 0))
  )
  (wire (pts (xy 154.94 24.765) (xy 165.1 24.765))
    (stroke (width 0) (type default) (color 0 0 0 0))
  )
  (wire (pts (xy 175.26 34.925) (xy 185.42 34.925))
    (stroke (width 0) (type default) (color 0 0 0 0))
  )
  (wire (pts (xy 254.635 61.595) (xy 292.735 61.595))
    (stroke (width 0) (type default) (color 0 0 0 0))
  )
  (wire (pts (xy 97.155 34.925) (xy 97.155 32.385))
    (stroke (width 0) (type default) (color 0 0 0 0))
  )
  (wire (pts (xy 324.485 185.42) (xy 384.81 185.42))
    (stroke (width 0) (type default) (color 0 0 0 0))
  )
  (wire (pts (xy 361.95 201.93) (xy 361.95 206.121))
    (stroke (width 0) (type default) (color 0 0 0 0))
  )
  (wire (pts (xy 281.94 92.71) (xy 281.94 104.14))
    (stroke (width 0) (type default) (color 0 0 0 0))
  )
  (wire (pts (xy 304.165 26.035) (xy 360.68 26.035))
    (stroke (width 0) (type default) (color 0 0 0 0))
  )
  (wire (pts (xy 107.315 34.925) (xy 97.155 34.925))
    (stroke (width 0) (type default) (color 0 0 0 0))
  )
  (wire (pts (xy 283.845 240.03) (xy 269.24 240.03))
    (stroke (width 0) (type default) (color 0 0 0 0))
  )
  (wire (pts (xy 103.505 57.15) (xy 103.505 59.69))
    (stroke (width 0) (type default) (color 0 0 0 0))
  )
  (wire (pts (xy 24.765 167.005) (xy 95.885 167.005))
    (stroke (width 0) (type default) (color 0 0 0 0))
  )
  (wire (pts (xy 273.685 158.75) (xy 273.685 170.18))
    (stroke (width 0) (type default) (color 0 0 0 0))
  )
  (wire (pts (xy 288.925 45.085) (xy 288.925 46.355))
    (stroke (width 0) (type default) (color 0 0 0 0))
  )
  (wire (pts (xy 47.625 55.245) (xy 67.31 55.245))
    (stroke (width 0) (type default) (color 0 0 0 0))
  )
  (wire (pts (xy 303.276 185.42) (xy 324.485 185.42))
    (stroke (width 0) (type default) (color 0 0 0 0))
  )
  (wire (pts (xy 128.905 135.255) (xy 189.23 135.255))
    (stroke (width 0) (type default) (color 0 0 0 0))
  )
  (wire (pts (xy 280.035 66.675) (xy 290.195 66.675))
    (stroke (width 0) (type default) (color 0 0 0 0))
  )
  (wire (pts (xy 272.415 84.328) (xy 272.415 90.17))
    (stroke (width 0) (type default) (color 0 0 0 0))
  )
  (wire (pts (xy 40.005 198.755) (xy 41.91 198.755))
    (stroke (width 0) (type default) (color 0 0 0 0))
  )
  (wire (pts (xy 185.42 24.765) (xy 185.42 27.305))
    (stroke (width 0) (type default) (color 0 0 0 0))
  )
  (wire (pts (xy 266.065 149.86) (xy 273.685 149.86))
    (stroke (width 0) (type default) (color 0 0 0 0))
  )
  (wire (pts (xy 333.375 180.34) (xy 401.955 180.34))
    (stroke (width 0) (type default) (color 0 0 0 0))
  )
  (wire (pts (xy 272.415 74.295) (xy 272.415 79.248))
    (stroke (width 0) (type default) (color 0 0 0 0))
  )
  (wire (pts (xy 304.165 23.495) (xy 363.22 23.495))
    (stroke (width 0) (type default) (color 0 0 0 0))
  )
  (wire (pts (xy 250.825 149.86) (xy 243.205 149.86))
    (stroke (width 0) (type default) (color 0 0 0 0))
  )
  (wire (pts (xy 47.625 45.085) (xy 66.421 45.085))
    (stroke (width 0) (type default) (color 0 0 0 0))
  )
  (wire (pts (xy 128.905 145.415) (xy 189.23 145.415))
    (stroke (width 0) (type default) (color 0 0 0 0))
  )
  (wire (pts (xy 332.74 46.355) (xy 332.74 80.01))
    (stroke (width 0) (type default) (color 0 0 0 0))
  )
  (wire (pts (xy 95.885 99.695) (xy 94.615 99.695))
    (stroke (width 0) (type default) (color 0 0 0 0))
  )
  (wire (pts (xy 332.74 46.355) (xy 375.92 46.355))
    (stroke (width 0) (type default) (color 0 0 0 0))
  )
  (wire (pts (xy 217.17 185.42) (xy 243.205 185.42))
    (stroke (width 0) (type default) (color 0 0 0 0))
  )
  (wire (pts (xy 403.352 74.295) (xy 403.352 75.946))
    (stroke (width 0) (type default) (color 0 0 0 0))
  )
  (wire (pts (xy 360.045 170.18) (xy 401.955 170.18))
    (stroke (width 0) (type default) (color 0 0 0 0))
  )
  (wire (pts (xy 117.475 32.385) (xy 117.475 34.925))
    (stroke (width 0) (type default) (color 0 0 0 0))
  )
  (wire (pts (xy 304.165 48.895) (xy 330.2 48.895))
    (stroke (width 0) (type default) (color 0 0 0 0))
  )
  (wire (pts (xy 167.005 127.635) (xy 189.23 127.635))
    (stroke (width 0) (type default) (color 0 0 0 0))
  )
  (wire (pts (xy 154.305 59.69) (xy 154.305 60.325))
    (stroke (width 0) (type default) (color 0 0 0 0))
  )
  (wire (pts (xy 272.415 73.66) (xy 272.415 74.295))
    (stroke (width 0) (type default) (color 0 0 0 0))
  )
  (wire (pts (xy 58.42 111.125) (xy 58.42 109.855))
    (stroke (width 0) (type default) (color 0 0 0 0))
  )
  (wire (pts (xy 58.42 126.365) (xy 95.885 126.365))
    (stroke (width 0) (type default) (color 0 0 0 0))
  )
  (wire (pts (xy 327.66 80.01) (xy 327.66 78.74))
    (stroke (width 0) (type default) (color 0 0 0 0))
  )
  (wire (pts (xy 360.045 201.93) (xy 361.95 201.93))
    (stroke (width 0) (type default) (color 0 0 0 0))
  )
  (wire (pts (xy 174.625 113.665) (xy 174.625 115.697))
    (stroke (width 0) (type default) (color 0 0 0 0))
  )
  (wire (pts (xy 34.417 45.085) (xy 47.625 45.085))
    (stroke (width 0) (type default) (color 0 0 0 0))
  )
  (wire (pts (xy 90.17 239.395) (xy 92.71 239.395))
    (stroke (width 0) (type default) (color 0 0 0 0))
  )
  (wire (pts (xy 168.275 236.22) (xy 172.085 236.22))
    (stroke (width 0) (type default) (color 0 0 0 0))
  )
  (wire (pts (xy 327.66 78.74) (xy 321.945 78.74))
    (stroke (width 0) (type default) (color 0 0 0 0))
  )
  (wire (pts (xy 94.615 111.125) (xy 95.885 111.125))
    (stroke (width 0) (type default) (color 0 0 0 0))
  )
  (wire (pts (xy 403.352 71.755) (xy 403.352 74.295))
    (stroke (width 0) (type default) (color 0 0 0 0))
  )
  (wire (pts (xy 103.505 49.53) (xy 103.505 52.07))
    (stroke (width 0) (type default) (color 0 0 0 0))
  )
  (wire (pts (xy 109.22 71.12) (xy 109.22 73.66))
    (stroke (width 0) (type default) (color 0 0 0 0))
  )
  (wire (pts (xy 342.265 177.8) (xy 401.955 177.8))
    (stroke (width 0) (type default) (color 0 0 0 0))
  )
  (wire (pts (xy 304.165 26.035) (xy 304.165 27.305))
    (stroke (width 0) (type default) (color 0 0 0 0))
  )
  (wire (pts (xy 133.985 49.53) (xy 144.145 49.53))
    (stroke (width 0) (type default) (color 0 0 0 0))
  )
  (wire (pts (xy 174.625 120.777) (xy 174.625 130.175))
    (stroke (width 0) (type default) (color 0 0 0 0))
  )
  (wire (pts (xy 165.1 34.925) (xy 154.94 34.925))
    (stroke (width 0) (type default) (color 0 0 0 0))
  )
  (wire (pts (xy 316.23 229.616) (xy 316.23 227.33))
    (stroke (width 0) (type default) (color 0 0 0 0))
  )
  (wire (pts (xy 335.28 41.275) (xy 375.92 41.275))
    (stroke (width 0) (type default) (color 0 0 0 0))
  )
  (wire (pts (xy 305.435 242.57) (xy 305.435 243.84))
    (stroke (width 0) (type default) (color 0 0 0 0))
  )
  (wire (pts (xy 181.356 246.38) (xy 200.66 246.38))
    (stroke (width 0) (type default) (color 0 0 0 0))
  )
  (wire (pts (xy 156.845 71.12) (xy 156.845 73.66))
    (stroke (width 0) (type default) (color 0 0 0 0))
  )
  (wire (pts (xy 403.352 66.675) (xy 403.352 69.215))
    (stroke (width 0) (type default) (color 0 0 0 0))
  )
  (wire (pts (xy 185.42 267.335) (xy 200.66 267.335))
    (stroke (width 0) (type default) (color 0 0 0 0))
  )
  (wire (pts (xy 185.42 32.385) (xy 185.42 34.925))
    (stroke (width 0) (type default) (color 0 0 0 0))
  )
  (wire (pts (xy 109.22 81.28) (xy 99.06 81.28))
    (stroke (width 0) (type default) (color 0 0 0 0))
  )
  (wire (pts (xy 288.925 158.75) (xy 288.925 162.56))
    (stroke (width 0) (type default) (color 0 0 0 0))
  )
  (wire (pts (xy 304.165 46.355) (xy 332.74 46.355))
    (stroke (width 0) (type default) (color 0 0 0 0))
  )
  (wire (pts (xy 219.075 34.925) (xy 219.075 36.195))
    (stroke (width 0) (type default) (color 0 0 0 0))
  )
  (wire (pts (xy 226.695 257.175) (xy 242.57 257.175))
    (stroke (width 0) (type default) (color 0 0 0 0))
  )
  (wire (pts (xy 59.055 184.785) (xy 60.325 184.785))
    (stroke (width 0) (type default) (color 0 0 0 0))
  )
  (wire (pts (xy 154.94 24.765) (xy 154.94 27.305))
    (stroke (width 0) (type default) (color 0 0 0 0))
  )
  (wire (pts (xy 219.075 24.765) (xy 219.075 27.305))
    (stroke (width 0) (type default) (color 0 0 0 0))
  )
  (wire (pts (xy 254.635 41.275) (xy 288.925 41.275))
    (stroke (width 0) (type default) (color 0 0 0 0))
  )
  (wire (pts (xy 337.82 38.735) (xy 375.92 38.735))
    (stroke (width 0) (type default) (color 0 0 0 0))
  )
  (wire (pts (xy 95.885 106.045) (xy 94.615 106.045))
    (stroke (width 0) (type default) (color 0 0 0 0))
  )
  (wire (pts (xy 235.585 149.86) (xy 235.585 153.67))
    (stroke (width 0) (type default) (color 0 0 0 0))
  )
  (wire (pts (xy 128.905 117.475) (xy 130.175 117.475))
    (stroke (width 0) (type default) (color 0 0 0 0))
  )
  (wire (pts (xy 146.685 71.12) (xy 146.685 73.66))
    (stroke (width 0) (type default) (color 0 0 0 0))
  )
  (wire (pts (xy 351.155 201.93) (xy 351.155 196.85))
    (stroke (width 0) (type default) (color 0 0 0 0))
  )
  (wire (pts (xy 269.24 242.57) (xy 269.24 240.03))
    (stroke (width 0) (type default) (color 0 0 0 0))
  )
  (wire (pts (xy 36.83 151.765) (xy 95.885 151.765))
    (stroke (width 0) (type default) (color 0 0 0 0))
  )
  (wire (pts (xy 182.245 267.335) (xy 185.42 267.335))
    (stroke (width 0) (type default) (color 0 0 0 0))
  )
  (wire (pts (xy 24.765 69.215) (xy 29.337 69.215))
    (stroke (width 0) (type default) (color 0 0 0 0))
  )
  (wire (pts (xy 47.625 69.215) (xy 67.056 69.215))
    (stroke (width 0) (type default) (color 0 0 0 0))
  )
  (wire (pts (xy 103.505 59.69) (xy 93.345 59.69))
    (stroke (width 0) (type default) (color 0 0 0 0))
  )
  (wire (pts (xy 304.165 48.895) (xy 304.165 50.165))
    (stroke (width 0) (type default) (color 0 0 0 0))
  )
  (wire (pts (xy 71.755 111.125) (xy 94.615 111.125))
    (stroke (width 0) (type default) (color 0 0 0 0))
  )
  (wire (pts (xy 271.78 242.57) (xy 271.78 237.49))
    (stroke (width 0) (type default) (color 0 0 0 0))
  )
  (wire (pts (xy 47.625 37.465) (xy 66.675 37.465))
    (stroke (width 0) (type default) (color 0 0 0 0))
  )
  (wire (pts (xy 130.175 102.235) (xy 130.175 106.045))
    (stroke (width 0) (type default) (color 0 0 0 0))
  )
  (wire (pts (xy 116.713 247.015) (xy 114.3 247.015))
    (stroke (width 0) (type default) (color 0 0 0 0))
  )
  (wire (pts (xy 217.17 187.96) (xy 235.585 187.96))
    (stroke (width 0) (type default) (color 0 0 0 0))
  )
  (wire (pts (xy 342.265 191.77) (xy 342.265 177.8))
    (stroke (width 0) (type default) (color 0 0 0 0))
  )
  (wire (pts (xy 250.825 149.86) (xy 250.825 153.67))
    (stroke (width 0) (type default) (color 0 0 0 0))
  )
  (wire (pts (xy 290.195 66.675) (xy 375.92 66.675))
    (stroke (width 0) (type default) (color 0 0 0 0))
  )
  (wire (pts (xy 288.925 42.545) (xy 288.925 41.275))
    (stroke (width 0) (type default) (color 0 0 0 0))
  )
  (wire (pts (xy 318.77 240.03) (xy 335.915 240.03))
    (stroke (width 0) (type default) (color 0 0 0 0))
  )
  (wire (pts (xy 315.595 196.85) (xy 315.595 201.93))
    (stroke (width 0) (type default) (color 0 0 0 0))
  )
  (wire (pts (xy 36.83 144.145) (xy 95.885 144.145))
    (stroke (width 0) (type default) (color 0 0 0 0))
  )
  (wire (pts (xy 34.417 37.465) (xy 47.625 37.465))
    (stroke (width 0) (type default) (color 0 0 0 0))
  )
  (wire (pts (xy 167.005 113.665) (xy 165.735 113.665))
    (stroke (width 0) (type default) (color 0 0 0 0))
  )
  (wire (pts (xy 304.165 33.655) (xy 355.6 33.655))
    (stroke (width 0) (type default) (color 0 0 0 0))
  )
  (wire (pts (xy 168.275 258.953) (xy 168.275 257.175))
    (stroke (width 0) (type default) (color 0 0 0 0))
  )
  (wire (pts (xy 168.275 264.033) (xy 168.275 267.335))
    (stroke (width 0) (type default) (color 0 0 0 0))
  )
  (wire (pts (xy 223.266 266.7) (xy 226.695 266.7))
    (stroke (width 0) (type default) (color 0 0 0 0))
  )
  (wire (pts (xy 335.28 41.275) (xy 335.28 80.01))
    (stroke (width 0) (type default) (color 0 0 0 0))
  )
  (wire (pts (xy 401.32 64.135) (xy 403.352 64.135))
    (stroke (width 0) (type default) (color 0 0 0 0))
  )
  (wire (pts (xy 167.005 120.777) (xy 167.005 127.635))
    (stroke (width 0) (type default) (color 0 0 0 0))
  )
  (wire (pts (xy 24.765 55.245) (xy 24.765 61.595))
    (stroke (width 0) (type default) (color 0 0 0 0))
  )
  (wire (pts (xy 128.905 132.715) (xy 189.23 132.715))
    (stroke (width 0) (type default) (color 0 0 0 0))
  )
  (wire (pts (xy 182.245 257.175) (xy 182.245 258.953))
    (stroke (width 0) (type default) (color 0 0 0 0))
  )
  (wire (pts (xy 24.765 172.085) (xy 95.885 172.085))
    (stroke (width 0) (type default) (color 0 0 0 0))
  )
  (wire (pts (xy 258.445 149.86) (xy 258.445 153.67))
    (stroke (width 0) (type default) (color 0 0 0 0))
  )
  (wire (pts (xy 216.535 245.745) (xy 216.535 249.555))
    (stroke (width 0) (type default) (color 0 0 0 0))
  )
  (wire (pts (xy 303.276 170.18) (xy 360.045 170.18))
    (stroke (width 0) (type default) (color 0 0 0 0))
  )
  (wire (pts (xy 403.352 61.595) (xy 403.352 64.135))
    (stroke (width 0) (type default) (color 0 0 0 0))
  )
  (wire (pts (xy 117.475 34.925) (xy 127.635 34.925))
    (stroke (width 0) (type default) (color 0 0 0 0))
  )
  (wire (pts (xy 128.905 150.495) (xy 189.23 150.495))
    (stroke (width 0) (type default) (color 0 0 0 0))
  )
  (wire (pts (xy 307.34 234.95) (xy 304.165 234.95))
    (stroke (width 0) (type default) (color 0 0 0 0))
  )
  (wire (pts (xy 88.265 182.245) (xy 95.885 182.245))
    (stroke (width 0) (type default) (color 0 0 0 0))
  )
  (wire (pts (xy 355.6 80.01) (xy 355.6 33.655))
    (stroke (width 0) (type default) (color 0 0 0 0))
  )
  (wire (pts (xy 76.835 177.165) (xy 76.835 179.705))
    (stroke (width 0) (type default) (color 0 0 0 0))
  )
  (wire (pts (xy 123.825 49.53) (xy 133.985 49.53))
    (stroke (width 0) (type default) (color 0 0 0 0))
  )
  (wire (pts (xy 36.83 139.065) (xy 95.885 139.065))
    (stroke (width 0) (type default) (color 0 0 0 0))
  )
  (wire (pts (xy 167.005 115.697) (xy 167.005 113.665))
    (stroke (width 0) (type default) (color 0 0 0 0))
  )
  (wire (pts (xy 254.635 38.735) (xy 288.925 38.735))
    (stroke (width 0) (type default) (color 0 0 0 0))
  )
  (wire (pts (xy 91.821 209.042) (xy 91.821 210.312))
    (stroke (width 0) (type default) (color 0 0 0 0))
  )
  (wire (pts (xy 91.821 209.042) (xy 94.234 209.042))
    (stroke (width 0) (type default) (color 0 0 0 0))
  )
  (wire (pts (xy 304.165 41.275) (xy 304.165 42.545))
    (stroke (width 0) (type default) (color 0 0 0 0))
  )
  (wire (pts (xy 288.925 34.925) (xy 288.925 33.655))
    (stroke (width 0) (type default) (color 0 0 0 0))
  )
  (wire (pts (xy 342.265 217.297) (xy 361.95 217.297))
    (stroke (width 0) (type default) (color 0 0 0 0))
  )
  (wire (pts (xy 50.8 111.125) (xy 50.8 109.855))
    (stroke (width 0) (type default) (color 0 0 0 0))
  )
  (wire (pts (xy 43.18 116.205) (xy 43.18 131.445))
    (stroke (width 0) (type default) (color 0 0 0 0))
  )
  (wire (pts (xy 363.22 23.495) (xy 363.22 80.01))
    (stroke (width 0) (type default) (color 0 0 0 0))
  )
  (wire (pts (xy 307.34 227.33) (xy 307.34 234.95))
    (stroke (width 0) (type default) (color 0 0 0 0))
  )
  (wire (pts (xy 353.06 80.01) (xy 353.06 78.74))
    (stroke (width 0) (type default) (color 0 0 0 0))
  )
  (wire (pts (xy 76.835 179.705) (xy 83.185 179.705))
    (stroke (width 0) (type default) (color 0 0 0 0))
  )
  (wire (pts (xy 243.205 185.42) (xy 298.196 185.42))
    (stroke (width 0) (type default) (color 0 0 0 0))
  )
  (wire (pts (xy 346.075 227.33) (xy 339.725 227.33))
    (stroke (width 0) (type default) (color 0 0 0 0))
  )
  (wire (pts (xy 23.495 55.245) (xy 24.765 55.245))
    (stroke (width 0) (type default) (color 0 0 0 0))
  )
  (wire (pts (xy 175.26 32.385) (xy 175.26 34.925))
    (stroke (width 0) (type default) (color 0 0 0 0))
  )
  (wire (pts (xy 78.105 24.765) (xy 97.155 24.765))
    (stroke (width 0) (type default) (color 0 0 0 0))
  )
  (wire (pts (xy 200.152 257.175) (xy 211.963 257.175))
    (stroke (width 0) (type default) (color 0 0 0 0))
  )
  (wire (pts (xy 43.18 131.445) (xy 24.13 131.445))
    (stroke (width 0) (type default) (color 0 0 0 0))
  )
  (wire (pts (xy 254.635 53.975) (xy 295.275 53.975))
    (stroke (width 0) (type default) (color 0 0 0 0))
  )
  (wire (pts (xy 43.18 131.445) (xy 95.885 131.445))
    (stroke (width 0) (type default) (color 0 0 0 0))
  )
  (wire (pts (xy 114.3 267.335) (xy 135.89 267.335))
    (stroke (width 0) (type default) (color 0 0 0 0))
  )
  (wire (pts (xy 36.83 136.525) (xy 95.885 136.525))
    (stroke (width 0) (type default) (color 0 0 0 0))
  )
  (wire (pts (xy 281.305 158.75) (xy 281.305 165.1))
    (stroke (width 0) (type default) (color 0 0 0 0))
  )
  (wire (pts (xy 304.165 31.115) (xy 304.165 29.845))
    (stroke (width 0) (type default) (color 0 0 0 0))
  )
  (wire (pts (xy 107.315 24.765) (xy 117.475 24.765))
    (stroke (width 0) (type default) (color 0 0 0 0))
  )
  (wire (pts (xy 265.43 237.49) (xy 271.78 237.49))
    (stroke (width 0) (type default) (color 0 0 0 0))
  )
  (wire (pts (xy 24.765 45.085) (xy 29.337 45.085))
    (stroke (width 0) (type default) (color 0 0 0 0))
  )
  (wire (pts (xy 389.89 215.265) (xy 389.89 212.725))
    (stroke (width 0) (type default) (color 0 0 0 0))
  )
  (wire (pts (xy 167.005 113.665) (xy 174.625 113.665))
    (stroke (width 0) (type default) (color 0 0 0 0))
  )
  (wire (pts (xy 76.835 184.785) (xy 76.835 182.245))
    (stroke (width 0) (type default) (color 0 0 0 0))
  )
  (wire (pts (xy 266.065 149.86) (xy 266.065 153.67))
    (stroke (width 0) (type default) (color 0 0 0 0))
  )
  (wire (pts (xy 355.6 33.655) (xy 375.92 33.655))
    (stroke (width 0) (type default) (color 0 0 0 0))
  )
  (wire (pts (xy 217.17 170.18) (xy 273.685 170.18))
    (stroke (width 0) (type default) (color 0 0 0 0))
  )
  (wire (pts (xy 288.925 162.56) (xy 298.196 162.56))
    (stroke (width 0) (type default) (color 0 0 0 0))
  )
  (wire (pts (xy 384.81 185.42) (xy 384.81 207.645))
    (stroke (width 0) (type default) (color 0 0 0 0))
  )
  (wire (pts (xy 134.62 231.775) (xy 134.62 238.76))
    (stroke (width 0) (type default) (color 0 0 0 0))
  )
  (wire (pts (xy 123.825 57.15) (xy 123.825 59.69))
    (stroke (width 0) (type default) (color 0 0 0 0))
  )
  (wire (pts (xy 128.905 106.045) (xy 130.175 106.045))
    (stroke (width 0) (type default) (color 0 0 0 0))
  )
  (wire (pts (xy 290.195 93.98) (xy 290.195 66.675))
    (stroke (width 0) (type default) (color 0 0 0 0))
  )
  (wire (pts (xy 94.615 113.665) (xy 94.615 111.125))
    (stroke (width 0) (type default) (color 0 0 0 0))
  )
  (wire (pts (xy 99.06 71.12) (xy 109.22 71.12))
    (stroke (width 0) (type default) (color 0 0 0 0))
  )
  (wire (pts (xy 43.18 109.855) (xy 43.18 111.125))
    (stroke (width 0) (type default) (color 0 0 0 0))
  )
  (wire (pts (xy 223.52 74.295) (xy 222.25 74.295))
    (stroke (width 0) (type default) (color 0 0 0 0))
  )
  (wire (pts (xy 95.885 113.665) (xy 94.615 113.665))
    (stroke (width 0) (type default) (color 0 0 0 0))
  )
  (wire (pts (xy 47.625 61.595) (xy 67.31 61.595))
    (stroke (width 0) (type default) (color 0 0 0 0))
  )
  (wire (pts (xy 283.845 242.57) (xy 280.67 242.57))
    (stroke (width 0) (type default) (color 0 0 0 0))
  )
  (wire (pts (xy 353.06 78.74) (xy 347.345 78.74))
    (stroke (width 0) (type default) (color 0 0 0 0))
  )
  (wire (pts (xy 69.85 183.515) (xy 69.85 184.785))
    (stroke (width 0) (type default) (color 0 0 0 0))
  )
  (wire (pts (xy 280.67 242.57) (xy 280.67 234.95))
    (stroke (width 0) (type default) (color 0 0 0 0))
  )
  (wire (pts (xy 266.065 158.75) (xy 266.065 172.72))
    (stroke (width 0) (type default) (color 0 0 0 0))
  )
  (wire (pts (xy 128.905 127.635) (xy 154.94 127.635))
    (stroke (width 0) (type default) (color 0 0 0 0))
  )
  (wire (pts (xy 324.485 201.93) (xy 333.375 201.93))
    (stroke (width 0) (type default) (color 0 0 0 0))
  )
  (wire (pts (xy 92.71 247.015) (xy 92.71 239.395))
    (stroke (width 0) (type default) (color 0 0 0 0))
  )
  (wire (pts (xy 128.27 234.95) (xy 129.54 234.95))
    (stroke (width 0) (type default) (color 0 0 0 0))
  )
  (wire (pts (xy 248.285 227.33) (xy 248.285 228.6))
    (stroke (width 0) (type default) (color 0 0 0 0))
  )
  (wire (pts (xy 69.85 177.165) (xy 69.85 178.435))
    (stroke (width 0) (type default) (color 0 0 0 0))
  )
  (wire (pts (xy 23.495 31.115) (xy 24.765 31.115))
    (stroke (width 0) (type default) (color 0 0 0 0))
  )
  (wire (pts (xy 34.417 69.215) (xy 47.625 69.215))
    (stroke (width 0) (type default) (color 0 0 0 0))
  )
  (wire (pts (xy 181.356 236.22) (xy 181.356 237.998))
    (stroke (width 0) (type default) (color 0 0 0 0))
  )
  (wire (pts (xy 254.635 56.515) (xy 297.815 56.515))
    (stroke (width 0) (type default) (color 0 0 0 0))
  )
  (wire (pts (xy 66.675 122.555) (xy 95.885 122.555))
    (stroke (width 0) (type default) (color 0 0 0 0))
  )
  (wire (pts (xy 116.205 272.415) (xy 114.3 272.415))
    (stroke (width 0) (type default) (color 0 0 0 0))
  )
  (wire (pts (xy 168.275 237.998) (xy 168.275 236.22))
    (stroke (width 0) (type default) (color 0 0 0 0))
  )
  (wire (pts (xy 269.24 235.077) (xy 269.24 240.03))
    (stroke (width 0) (type default) (color 0 0 0 0))
  )
  (wire (pts (xy 211.963 257.175) (xy 211.963 266.7))
    (stroke (width 0) (type default) (color 0 0 0 0))
  )
  (wire (pts (xy 93.345 49.53) (xy 93.345 52.07))
    (stroke (width 0) (type default) (color 0 0 0 0))
  )
  (wire (pts (xy 288.925 37.465) (xy 288.925 38.735))
    (stroke (width 0) (type default) (color 0 0 0 0))
  )
  (wire (pts (xy 93.98 247.015) (xy 92.71 247.015))
    (stroke (width 0) (type default) (color 0 0 0 0))
  )
  (wire (pts (xy 172.085 257.175) (xy 172.085 259.715))
    (stroke (width 0) (type default) (color 0 0 0 0))
  )
  (wire (pts (xy 174.625 130.175) (xy 189.23 130.175))
    (stroke (width 0) (type default) (color 0 0 0 0))
  )
  (wire (pts (xy 160.655 130.175) (xy 174.625 130.175))
    (stroke (width 0) (type default) (color 0 0 0 0))
  )
  (wire (pts (xy 337.82 38.735) (xy 337.82 80.01))
    (stroke (width 0) (type default) (color 0 0 0 0))
  )
  (wire (pts (xy 281.94 92.71) (xy 287.655 92.71))
    (stroke (width 0) (type default) (color 0 0 0 0))
  )
  (wire (pts (xy 71.755 99.695) (xy 94.615 99.695))
    (stroke (width 0) (type default) (color 0 0 0 0))
  )
  (wire (pts (xy 211.963 257.175) (xy 212.725 257.175))
    (stroke (width 0) (type default) (color 0 0 0 0))
  )
  (wire (pts (xy 269.24 240.03) (xy 265.43 240.03))
    (stroke (width 0) (type default) (color 0 0 0 0))
  )
  (wire (pts (xy 116.205 273.431) (xy 116.205 272.415))
    (stroke (width 0) (type default) (color 0 0 0 0))
  )
  (wire (pts (xy 295.275 53.975) (xy 375.92 53.975))
    (stroke (width 0) (type default) (color 0 0 0 0))
  )
  (wire (pts (xy 254.635 23.495) (xy 288.925 23.495))
    (stroke (width 0) (type default) (color 0 0 0 0))
  )
  (wire (pts (xy 219.075 32.385) (xy 219.075 34.925))
    (stroke (width 0) (type default) (color 0 0 0 0))
  )
  (wire (pts (xy 252.095 74.295) (xy 272.415 74.295))
    (stroke (width 0) (type default) (color 0 0 0 0))
  )
  (wire (pts (xy 128.905 147.955) (xy 189.23 147.955))
    (stroke (width 0) (type default) (color 0 0 0 0))
  )
  (wire (pts (xy 208.915 24.765) (xy 208.915 27.305))
    (stroke (width 0) (type default) (color 0 0 0 0))
  )
  (wire (pts (xy 109.22 71.12) (xy 119.38 71.12))
    (stroke (width 0) (type default) (color 0 0 0 0))
  )
  (wire (pts (xy 280.67 234.95) (xy 283.845 234.95))
    (stroke (width 0) (type default) (color 0 0 0 0))
  )
  (wire (pts (xy 258.445 149.86) (xy 250.825 149.86))
    (stroke (width 0) (type default) (color 0 0 0 0))
  )
  (wire (pts (xy 41.91 187.325) (xy 41.91 191.262))
    (stroke (width 0) (type default) (color 0 0 0 0))
  )
  (wire (pts (xy 403.352 69.215) (xy 403.352 71.755))
    (stroke (width 0) (type default) (color 0 0 0 0))
  )
  (wire (pts (xy 135.255 24.765) (xy 154.94 24.765))
    (stroke (width 0) (type default) (color 0 0 0 0))
  )
  (wire (pts (xy 287.655 92.71) (xy 287.655 93.98))
    (stroke (width 0) (type default) (color 0 0 0 0))
  )
  (wire (pts (xy 226.695 235.585) (xy 216.535 235.585))
    (stroke (width 0) (type default) (color 0 0 0 0))
  )
  (wire (pts (xy 333.375 201.93) (xy 342.265 201.93))
    (stroke (width 0) (type default) (color 0 0 0 0))
  )
  (wire (pts (xy 93.345 59.69) (xy 93.345 57.15))
    (stroke (width 0) (type default) (color 0 0 0 0))
  )
  (wire (pts (xy 93.98 272.415) (xy 92.71 272.415))
    (stroke (width 0) (type default) (color 0 0 0 0))
  )
  (wire (pts (xy 24.765 31.115) (xy 24.765 37.465))
    (stroke (width 0) (type default) (color 0 0 0 0))
  )
  (wire (pts (xy 243.205 149.86) (xy 243.205 153.67))
    (stroke (width 0) (type default) (color 0 0 0 0))
  )
  (wire (pts (xy 94.234 203.835) (xy 94.234 209.042))
    (stroke (width 0) (type default) (color 0 0 0 0))
  )
  (wire (pts (xy 339.725 227.33) (xy 339.725 228.6))
    (stroke (width 0) (type default) (color 0 0 0 0))
  )
  (wire (pts (xy 163.195 246.38) (xy 168.275 246.38))
    (stroke (width 0) (type default) (color 0 0 0 0))
  )
  (wire (pts (xy 93.98 267.335) (xy 90.17 267.335))
    (stroke (width 0) (type default) (color 0 0 0 0))
  )
  (wire (pts (xy 241.935 227.33) (xy 248.285 227.33))
    (stroke (width 0) (type default) (color 0 0 0 0))
  )
  (wire (pts (xy 185.42 268.605) (xy 185.42 267.335))
    (stroke (width 0) (type default) (color 0 0 0 0))
  )
  (wire (pts (xy 377.825 191.77) (xy 377.825 162.56))
    (stroke (width 0) (type default) (color 0 0 0 0))
  )
  (wire (pts (xy 401.32 74.295) (xy 403.352 74.295))
    (stroke (width 0) (type default) (color 0 0 0 0))
  )
  (wire (pts (xy 288.925 149.86) (xy 288.925 153.67))
    (stroke (width 0) (type default) (color 0 0 0 0))
  )
  (wire (pts (xy 180.975 246.38) (xy 181.356 246.38))
    (stroke (width 0) (type default) (color 0 0 0 0))
  )
  (wire (pts (xy 156.845 81.28) (xy 146.685 81.28))
    (stroke (width 0) (type default) (color 0 0 0 0))
  )
  (wire (pts (xy 119.38 71.12) (xy 119.38 73.66))
    (stroke (width 0) (type default) (color 0 0 0 0))
  )
  (wire (pts (xy 94.615 102.235) (xy 94.615 99.695))
    (stroke (width 0) (type default) (color 0 0 0 0))
  )
  (wire (pts (xy 154.305 49.53) (xy 154.305 52.07))
    (stroke (width 0) (type default) (color 0 0 0 0))
  )
  (wire (pts (xy 175.26 24.765) (xy 175.26 27.305))
    (stroke (width 0) (type default) (color 0 0 0 0))
  )
  (wire (pts (xy 295.275 53.975) (xy 295.275 93.98))
    (stroke (width 0) (type default) (color 0 0 0 0))
  )
  (wire (pts (xy 297.815 56.515) (xy 375.92 56.515))
    (stroke (width 0) (type default) (color 0 0 0 0))
  )
  (wire (pts (xy 401.32 66.675) (xy 403.352 66.675))
    (stroke (width 0) (type default) (color 0 0 0 0))
  )
  (wire (pts (xy 271.78 227.33) (xy 280.67 227.33))
    (stroke (width 0) (type default) (color 0 0 0 0))
  )
  (wire (pts (xy 318.77 234.696) (xy 318.77 240.03))
    (stroke (width 0) (type default) (color 0 0 0 0))
  )
  (wire (pts (xy 211.963 266.7) (xy 218.186 266.7))
    (stroke (width 0) (type default) (color 0 0 0 0))
  )
  (wire (pts (xy 119.38 78.74) (xy 119.38 81.28))
    (stroke (width 0) (type default) (color 0 0 0 0))
  )
  (wire (pts (xy 304.165 237.49) (xy 316.23 237.49))
    (stroke (width 0) (type default) (color 0 0 0 0))
  )
  (wire (pts (xy 24.765 55.245) (xy 29.337 55.245))
    (stroke (width 0) (type default) (color 0 0 0 0))
  )
  (wire (pts (xy 258.445 177.8) (xy 298.196 177.8))
    (stroke (width 0) (type default) (color 0 0 0 0))
  )
  (wire (pts (xy 347.345 78.74) (xy 347.345 90.17))
    (stroke (width 0) (type default) (color 0 0 0 0))
  )
  (wire (pts (xy 368.935 201.93) (xy 377.825 201.93))
    (stroke (width 0) (type default) (color 0 0 0 0))
  )
  (wire (pts (xy 95.885 203.835) (xy 94.234 203.835))
    (stroke (width 0) (type default) (color 0 0 0 0))
  )
  (wire (pts (xy 114.3 262.255) (xy 135.89 262.255))
    (stroke (width 0) (type default) (color 0 0 0 0))
  )
  (wire (pts (xy 185.42 34.925) (xy 185.42 36.195))
    (stroke (width 0) (type default) (color 0 0 0 0))
  )
  (wire (pts (xy 368.935 201.93) (xy 368.935 196.85))
    (stroke (width 0) (type default) (color 0 0 0 0))
  )
  (wire (pts (xy 318.77 229.616) (xy 318.77 227.33))
    (stroke (width 0) (type default) (color 0 0 0 0))
  )
  (wire (pts (xy 59.055 177.165) (xy 59.055 184.785))
    (stroke (width 0) (type default) (color 0 0 0 0))
  )
  (wire (pts (xy 303.276 177.8) (xy 342.265 177.8))
    (stroke (width 0) (type default) (color 0 0 0 0))
  )
  (wire (pts (xy 217.17 177.8) (xy 258.445 177.8))
    (stroke (width 0) (type default) (color 0 0 0 0))
  )
  (wire (pts (xy 97.155 24.765) (xy 107.315 24.765))
    (stroke (width 0) (type default) (color 0 0 0 0))
  )
  (wire (pts (xy 324.485 201.93) (xy 324.485 196.85))
    (stroke (width 0) (type default) (color 0 0 0 0))
  )
  (wire (pts (xy 93.345 49.53) (xy 103.505 49.53))
    (stroke (width 0) (type default) (color 0 0 0 0))
  )
  (wire (pts (xy 360.68 26.035) (xy 375.92 26.035))
    (stroke (width 0) (type default) (color 0 0 0 0))
  )
  (wire (pts (xy 384.81 212.725) (xy 384.81 215.265))
    (stroke (width 0) (type default) (color 0 0 0 0))
  )
  (wire (pts (xy 50.8 128.905) (xy 95.885 128.905))
    (stroke (width 0) (type default) (color 0 0 0 0))
  )
  (wire (pts (xy 93.98 262.255) (xy 90.17 262.255))
    (stroke (width 0) (type default) (color 0 0 0 0))
  )
  (wire (pts (xy 280.035 66.675) (xy 254.635 66.675))
    (stroke (width 0) (type default) (color 0 0 0 0))
  )
  (wire (pts (xy 165.1 32.385) (xy 165.1 34.925))
    (stroke (width 0) (type default) (color 0 0 0 0))
  )
  (wire (pts (xy 130.175 117.475) (xy 130.175 114.935))
    (stroke (width 0) (type default) (color 0 0 0 0))
  )
  (wire (pts (xy 235.585 187.96) (xy 295.021 187.96))
    (stroke (width 0) (type default) (color 0 0 0 0))
  )
  (wire (pts (xy 226.695 237.236) (xy 226.695 235.585))
    (stroke (width 0) (type default) (color 0 0 0 0))
  )
  (wire (pts (xy 36.83 149.225) (xy 95.885 149.225))
    (stroke (width 0) (type default) (color 0 0 0 0))
  )
  (wire (pts (xy 377.825 162.56) (xy 401.955 162.56))
    (stroke (width 0) (type default) (color 0 0 0 0))
  )
  (wire (pts (xy 342.265 201.93) (xy 342.265 203.2))
    (stroke (width 0) (type default) (color 0 0 0 0))
  )
  (wire (pts (xy 91.821 207.772) (xy 91.821 209.042))
    (stroke (width 0) (type default) (color 0 0 0 0))
  )
  (wire (pts (xy 254.635 31.115) (xy 288.925 31.115))
    (stroke (width 0) (type default) (color 0 0 0 0))
  )
  (wire (pts (xy 172.72 155.575) (xy 189.23 155.575))
    (stroke (width 0) (type default) (color 0 0 0 0))
  )
  (wire (pts (xy 250.825 158.75) (xy 250.825 180.34))
    (stroke (width 0) (type default) (color 0 0 0 0))
  )
  (wire (pts (xy 333.375 201.93) (xy 333.375 196.85))
    (stroke (width 0) (type default) (color 0 0 0 0))
  )
  (wire (pts (xy 160.401 155.575) (xy 167.64 155.575))
    (stroke (width 0) (type default) (color 0 0 0 0))
  )
  (wire (pts (xy 72.39 117.475) (xy 95.885 117.475))
    (stroke (width 0) (type default) (color 0 0 0 0))
  )
  (wire (pts (xy 144.145 49.53) (xy 144.145 52.07))
    (stroke (width 0) (type default) (color 0 0 0 0))
  )
  (wire (pts (xy 165.1 24.765) (xy 175.26 24.765))
    (stroke (width 0) (type default) (color 0 0 0 0))
  )
  (wire (pts (xy 300.101 172.72) (xy 351.155 172.72))
    (stroke (width 0) (type default) (color 0 0 0 0))
  )
  (wire (pts (xy 368.935 165.1) (xy 368.935 191.77))
    (stroke (width 0) (type default) (color 0 0 0 0))
  )
  (wire (pts (xy 99.06 71.12) (xy 99.06 73.66))
    (stroke (width 0) (type default) (color 0 0 0 0))
  )
  (wire (pts (xy 109.22 78.74) (xy 109.22 81.28))
    (stroke (width 0) (type default) (color 0 0 0 0))
  )
  (wire (pts (xy 342.265 217.297) (xy 342.265 218.567))
    (stroke (width 0) (type default) (color 0 0 0 0))
  )
  (wire (pts (xy 288.925 22.225) (xy 288.925 23.495))
    (stroke (width 0) (type default) (color 0 0 0 0))
  )
  (wire (pts (xy 182.245 264.033) (xy 182.245 267.335))
    (stroke (width 0) (type default) (color 0 0 0 0))
  )
  (wire (pts (xy 58.42 109.855) (xy 66.675 109.855))
    (stroke (width 0) (type default) (color 0 0 0 0))
  )
  (wire (pts (xy 384.81 215.265) (xy 384.81 216.535))
    (stroke (width 0) (type default) (color 0 0 0 0))
  )
  (wire (pts (xy 217.17 149.86) (xy 235.585 149.86))
    (stroke (width 0) (type default) (color 0 0 0 0))
  )
  (wire (pts (xy 91.821 201.295) (xy 91.821 202.692))
    (stroke (width 0) (type default) (color 0 0 0 0))
  )
  (wire (pts (xy 130.175 108.585) (xy 130.175 111.125))
    (stroke (width 0) (type default) (color 0 0 0 0))
  )
  (wire (pts (xy 69.85 177.165) (xy 76.835 177.165))
    (stroke (width 0) (type default) (color 0 0 0 0))
  )
  (wire (pts (xy 342.265 201.93) (xy 342.265 196.85))
    (stroke (width 0) (type default) (color 0 0 0 0))
  )
  (wire (pts (xy 271.78 237.49) (xy 283.845 237.49))
    (stroke (width 0) (type default) (color 0 0 0 0))
  )
  (wire (pts (xy 244.475 74.295) (xy 228.6 74.295))
    (stroke (width 0) (type default) (color 0 0 0 0))
  )
  (wire (pts (xy 288.925 27.305) (xy 288.925 26.035))
    (stroke (width 0) (type default) (color 0 0 0 0))
  )
  (wire (pts (xy 24.13 128.905) (xy 50.8 128.905))
    (stroke (width 0) (type default) (color 0 0 0 0))
  )
  (wire (pts (xy 243.205 149.86) (xy 235.585 149.86))
    (stroke (width 0) (type default) (color 0 0 0 0))
  )
  (wire (pts (xy 127.635 32.385) (xy 127.635 34.925))
    (stroke (width 0) (type default) (color 0 0 0 0))
  )
  (wire (pts (xy 24.765 61.595) (xy 24.765 69.215))
    (stroke (width 0) (type default) (color 0 0 0 0))
  )
  (wire (pts (xy 168.275 257.175) (xy 172.085 257.175))
    (stroke (width 0) (type default) (color 0 0 0 0))
  )
  (wire (pts (xy 401.32 61.595) (xy 403.352 61.595))
    (stroke (width 0) (type default) (color 0 0 0 0))
  )
  (wire (pts (xy 127.635 34.925) (xy 127.635 36.195))
    (stroke (width 0) (type default) (color 0 0 0 0))
  )

  (text "Note:\nplace close to\npin 17 of U2" (at 193.675 275.59 0)
    (effects (font (size 1.27 1.27)) (justify left bottom))
  )
  (text "HDMI converter" (at 12.7 17.78 0)
    (effects (font (size 2.9972 2.9972) (thickness 0.5994) bold) (justify left bottom))
  )

  (label "HDMI_CLK_P" (at 401.955 185.42 180)
    (effects (font (size 1.27 1.27)) (justify right bottom))
  )
  (label "LT9611_VCC12_TX" (at 149.86 122.555 180)
    (effects (font (size 1.27 1.27)) (justify right bottom))
  )
  (label "HDMI_TX1_N" (at 401.955 172.72 180)
    (effects (font (size 1.27 1.27)) (justify right bottom))
  )
  (label "HDMI_TX1_P" (at 401.955 170.18 180)
    (effects (font (size 1.27 1.27)) (justify right bottom))
  )
  (label "HDMI_TX1_P" (at 254.635 31.115 0)
    (effects (font (size 1.27 1.27)) (justify left bottom))
  )
  (label "LT9611_VCC33_TX" (at 66.421 45.085 180)
    (effects (font (size 1.27 1.27)) (justify right bottom))
  )
  (label "LT9611_VCC33_TX" (at 189.865 24.765 0)
    (effects (font (size 1.27 1.27)) (justify left bottom))
  )
  (label "LT9611_SCL" (at 24.13 126.365 0)
    (effects (font (size 1.27 1.27)) (justify left bottom))
  )
  (label "LT9611_VCC33_TX" (at 72.39 117.475 0)
    (effects (font (size 1.27 1.27)) (justify left bottom))
  )
  (label "HDMI_TX_CLK_P" (at 189.23 147.955 180)
    (effects (font (size 1.27 1.27)) (justify right bottom))
  )
  (label "HDMI_SDA" (at 189.23 130.175 180)
    (effects (font (size 1.27 1.27)) (justify right bottom))
  )
  (label "VCOM" (at 217.17 201.93 0)
    (effects (font (size 1.27 1.27)) (justify left bottom))
  )
  (label "LT9611_SCL" (at 335.915 237.49 180)
    (effects (font (size 1.27 1.27)) (justify right bottom))
  )
  (label "LT9611_I2S_D0_SPDIF" (at 135.89 267.335 180)
    (effects (font (size 1.27 1.27)) (justify right bottom))
  )
  (label "HDMI_CLK_CONN_P" (at 306.07 46.355 0)
    (effects (font (size 1.27 1.27)) (justify left bottom))
  )
  (label "LT9611_VDD12" (at 67.31 55.245 180)
    (effects (font (size 1.27 1.27)) (justify right bottom))
  )
  (label "LT9611_RST_N" (at 24.13 131.445 0)
    (effects (font (size 1.27 1.27)) (justify left bottom))
  )
  (label "HDMI_TX_D2_N" (at 217.17 165.1 0)
    (effects (font (size 1.27 1.27)) (justify left bottom))
  )
  (label "HDMI_SCL" (at 254.635 53.975 0)
    (effects (font (size 1.27 1.27)) (justify left bottom))
  )
  (label "LT9611_VCC33_RX" (at 66.675 37.465 180)
    (effects (font (size 1.27 1.27)) (justify right bottom))
  )
  (label "HDMI_TX0_CONN_P" (at 306.07 38.735 0)
    (effects (font (size 1.27 1.27)) (justify left bottom))
  )
  (label "LT9611_CEC" (at 189.23 153.035 180)
    (effects (font (size 1.27 1.27)) (justify right bottom))
  )
  (label "LT9611_VCC12_TX" (at 67.056 69.215 180)
    (effects (font (size 1.27 1.27)) (justify right bottom))
  )
  (label "I2C_ADDR" (at 74.93 198.755 180)
    (effects (font (size 1.27 1.27)) (justify right bottom))
  )
  (label "LT9611_I2S_MCLK" (at 24.765 169.545 0)
    (effects (font (size 1.27 1.27)) (justify left bottom))
  )
  (label "HDMI_TX_D1_N" (at 217.17 172.72 0)
    (effects (font (size 1.27 1.27)) (justify left bottom))
  )
  (label "HDMI_TX_CLK_N" (at 217.17 187.96 0)
    (effects (font (size 1.27 1.27)) (justify left bottom))
  )
  (label "HDMI_CEC" (at 242.57 257.175 180)
    (effects (font (size 1.27 1.27)) (justify right bottom))
  )
  (label "HDMI_CLK_P" (at 254.635 46.355 0)
    (effects (font (size 1.27 1.27)) (justify left bottom))
  )
  (label "HDMI_SDA" (at 254.635 56.515 0)
    (effects (font (size 1.27 1.27)) (justify left bottom))
  )
  (label "HDMI_TX_D1_P" (at 217.17 170.18 0)
    (effects (font (size 1.27 1.27)) (justify left bottom))
  )
  (label "HDMI_TX_D0_P" (at 189.23 142.875 180)
    (effects (font (size 1.27 1.27)) (justify right bottom))
  )
  (label "HDMI_CLK_CONN_N" (at 306.07 48.895 0)
    (effects (font (size 1.27 1.27)) (justify left bottom))
  )
  (label "LT9611_SDA" (at 335.915 240.03 180)
    (effects (font (size 1.27 1.27)) (justify right bottom))
  )
  (label "HDMI_TX2_N" (at 254.635 26.035 0)
    (effects (font (size 1.27 1.27)) (justify left bottom))
  )
  (label "LT9611_SDA" (at 24.13 128.905 0)
    (effects (font (size 1.27 1.27)) (justify left bottom))
  )
  (label "HDMI_TX1_N" (at 254.635 33.655 0)
    (effects (font (size 1.27 1.27)) (justify left bottom))
  )
  (label "HDMI_TX1_CONN_P" (at 306.07 31.115 0)
    (effects (font (size 1.27 1.27)) (justify left bottom))
  )
  (label "LT9611_VCC33_RX" (at 135.255 24.765 0)
    (effects (font (size 1.27 1.27)) (justify left bottom))
  )
  (label "HDMI_TX1_CONN_N" (at 306.07 33.655 0)
    (effects (font (size 1.27 1.27)) (justify left bottom))
  )
  (label "HDMI_TX0_N" (at 254.635 41.275 0)
    (effects (font (size 1.27 1.27)) (justify left bottom))
  )
  (label "HDMI_DETECT" (at 189.23 155.575 180)
    (effects (font (size 1.27 1.27)) (justify right bottom))
  )
  (label "HDMI_TX2_N" (at 401.955 165.1 180)
    (effects (font (size 1.27 1.27)) (justify right bottom))
  )
  (label "HDMI_TX_D0_N" (at 217.17 180.34 0)
    (effects (font (size 1.27 1.27)) (justify left bottom))
  )
  (label "HDMI_TX2_P" (at 401.955 162.56 180)
    (effects (font (size 1.27 1.27)) (justify right bottom))
  )
  (label "LT9611_VCC12_RX" (at 67.31 61.595 180)
    (effects (font (size 1.27 1.27)) (justify right bottom))
  )
  (label "LT9611_VCC33_TX" (at 217.17 149.86 0)
    (effects (font (size 1.27 1.27)) (justify left bottom))
  )
  (label "5V_HDMI" (at 254.635 74.295 0)
    (effects (font (size 1.27 1.27)) (justify left bottom))
  )
  (label "LT9611_I2S_WS" (at 135.89 252.095 180)
    (effects (font (size 1.27 1.27)) (justify right bottom))
  )
  (label "HDMI_CEC" (at 254.635 61.595 0)
    (effects (font (size 1.27 1.27)) (justify left bottom))
  )
  (label "HDMI_TX2_CONN_N" (at 306.07 26.035 0)
    (effects (font (size 1.27 1.27)) (justify left bottom))
  )
  (label "LT9611_INTO_GPIO5" (at 24.13 122.555 0)
    (effects (font (size 1.27 1.27)) (justify left bottom))
  )
  (label "HDMI_TX2_CONN_P" (at 306.07 23.495 0)
    (effects (font (size 1.27 1.27)) (justify left bottom))
  )
  (label "HDMI_TX2_P" (at 254.635 23.495 0)
    (effects (font (size 1.27 1.27)) (justify left bottom))
  )
  (label "HDMI_TX0_CONN_N" (at 306.07 41.275 0)
    (effects (font (size 1.27 1.27)) (justify left bottom))
  )
  (label "HDMI_TX_D1_N" (at 189.23 140.335 180)
    (effects (font (size 1.27 1.27)) (justify right bottom))
  )
  (label "LT9611_I2S_MCLK" (at 135.89 262.255 180)
    (effects (font (size 1.27 1.27)) (justify right bottom))
  )
  (label "LT9611_I2S_D0_SPDIF" (at 24.765 172.085 0)
    (effects (font (size 1.27 1.27)) (justify left bottom))
  )
  (label "HDMI_TX_D2_P" (at 189.23 132.715 180)
    (effects (font (size 1.27 1.27)) (justify right bottom))
  )
  (label "HDMI_CLK_N" (at 254.635 48.895 0)
    (effects (font (size 1.27 1.27)) (justify left bottom))
  )
  (label "XTALI" (at 95.25 182.245 180)
    (effects (font (size 1.27 1.27)) (justify right bottom))
  )
  (label "HDMI_TX_D0_P" (at 217.17 177.8 0)
    (effects (font (size 1.27 1.27)) (justify left bottom))
  )
  (label "LT9611_VCC33_IO" (at 71.755 111.125 0)
    (effects (font (size 1.27 1.27)) (justify left bottom))
  )
  (label "HDMI_CLK_N" (at 401.955 187.96 180)
    (effects (font (size 1.27 1.27)) (justify right bottom))
  )
  (label "5V_HDMI_FB_D" (at 229.616 74.295 0)
    (effects (font (size 1.27 1.27)) (justify left bottom))
  )
  (label "HDMI_TX_D0_N" (at 189.23 145.415 180)
    (effects (font (size 1.27 1.27)) (justify right bottom))
  )
  (label "HDMI_SCL" (at 189.23 127.635 180)
    (effects (font (size 1.27 1.27)) (justify right bottom))
  )
  (label "LT9611_VDD12" (at 149.86 99.695 180)
    (effects (font (size 1.27 1.27)) (justify right bottom))
  )
  (label "HDMI_TX_D2_N" (at 189.23 135.255 180)
    (effects (font (size 1.27 1.27)) (justify right bottom))
  )
  (label "LT9611_VDD12" (at 78.105 49.53 0)
    (effects (font (size 1.27 1.27)) (justify left bottom))
  )
  (label "HDMI_TX_CLK_P" (at 217.17 185.42 0)
    (effects (font (size 1.27 1.27)) (justify left bottom))
  )
  (label "HDMI_TX_CLK_N" (at 189.23 150.495 180)
    (effects (font (size 1.27 1.27)) (justify right bottom))
  )
  (label "HDMI_TX0_P" (at 401.955 177.8 180)
    (effects (font (size 1.27 1.27)) (justify right bottom))
  )
  (label "HDMI_TX0_P" (at 254.635 38.735 0)
    (effects (font (size 1.27 1.27)) (justify left bottom))
  )
  (label "HDMI_TX_D1_P" (at 189.23 137.795 180)
    (effects (font (size 1.27 1.27)) (justify right bottom))
  )
  (label "LT9611_VCC33_IO" (at 78.105 24.765 0)
    (effects (font (size 1.27 1.27)) (justify left bottom))
  )
  (label "VCOM" (at 189.23 203.835 180)
    (effects (font (size 1.27 1.27)) (justify right bottom))
  )
  (label "HDMI_TX_D2_P" (at 217.17 162.56 0)
    (effects (font (size 1.27 1.27)) (justify left bottom))
  )
  (label "LT9611_CEC" (at 200.152 257.175 0)
    (effects (font (size 1.27 1.27)) (justify left bottom))
  )
  (label "LT9611_VCC33_RX" (at 71.755 99.695 0)
    (effects (font (size 1.27 1.27)) (justify left bottom))
  )
  (label "XTALO" (at 95.885 179.705 180)
    (effects (font (size 1.27 1.27)) (justify right bottom))
  )
  (label "LT9611_VCC12_TX" (at 126.365 71.12 0)
    (effects (font (size 1.27 1.27)) (justify left bottom))
  )
  (label "HDMI_TX0_N" (at 401.955 180.34 180)
    (effects (font (size 1.27 1.27)) (justify right bottom))
  )
  (label "LT9611_VCC12_RX" (at 149.86 114.935 180)
    (effects (font (size 1.27 1.27)) (justify right bottom))
  )
  (label "LT9611_I2S_SCLK" (at 135.89 257.175 180)
    (effects (font (size 1.27 1.27)) (justify right bottom))
  )
  (label "LT9611_VCC12_RX" (at 79.375 71.12 0)
    (effects (font (size 1.27 1.27)) (justify left bottom))
  )
  (label "LT9611_RST_N" (at 200.66 267.335 180)
    (effects (font (size 1.27 1.27)) (justify right bottom))
  )
  (label "LT9611_VCC33_IO" (at 66.675 31.115 180)
    (effects (font (size 1.27 1.27)) (justify right bottom))
  )
  (label "LT9611_I2S_WS" (at 24.765 164.465 0)
    (effects (font (size 1.27 1.27)) (justify left bottom))
  )
  (label "LT9611_INTO_GPIO5" (at 200.66 246.38 180)
    (effects (font (size 1.27 1.27)) (justify right bottom))
  )
  (label "LT9611_I2S_SCLK" (at 24.765 167.005 0)
    (effects (font (size 1.27 1.27)) (justify left bottom))
  )
  (label "HDMI_DETECT" (at 254.635 66.675 0)
    (effects (font (size 1.27 1.27)) (justify left bottom))
  )

  (global_label "DSI1_LN3_N" (shape input) (at 36.83 136.525 180) (fields_autoplaced)
    (effects (font (size 1.27 1.27)) (justify right))
    (property "Intersheet References" "${INTERSHEET_REFS}" (id 0) (at 0 1.27 0)
      (effects (font (size 1.27 1.27)) hide)
    )
  )
  (global_label "VREG_S4A_1V8" (shape input) (at 128.27 234.95 180) (fields_autoplaced)
    (effects (font (size 1.27 1.27)) (justify right))
    (property "Intersheet References" "${INTERSHEET_REFS}" (id 0) (at 0 0 0)
      (effects (font (size 1.27 1.27)) hide)
    )
  )
  (global_label "3V3_SYS" (shape input) (at 182.626 236.22 0) (fields_autoplaced)
    (effects (font (size 1.27 1.27)) (justify left))
    (property "Intersheet References" "${INTERSHEET_REFS}" (id 0) (at -0.889 0 0)
      (effects (font (size 1.27 1.27)) hide)
    )
  )
  (global_label "DSI1_LN0_N" (shape input) (at 36.83 156.845 180) (fields_autoplaced)
    (effects (font (size 1.27 1.27)) (justify right))
    (property "Intersheet References" "${INTERSHEET_REFS}" (id 0) (at 0 1.27 0)
      (effects (font (size 1.27 1.27)) hide)
    )
  )
  (global_label "DSI1_LN3_P" (shape input) (at 36.83 139.065 180) (fields_autoplaced)
    (effects (font (size 1.27 1.27)) (justify right))
    (property "Intersheet References" "${INTERSHEET_REFS}" (id 0) (at 0 1.27 0)
      (effects (font (size 1.27 1.27)) hide)
    )
  )
  (global_label "DSI1_CLK_P" (shape input) (at 36.83 149.225 180) (fields_autoplaced)
    (effects (font (size 1.27 1.27)) (justify right))
    (property "Intersheet References" "${INTERSHEET_REFS}" (id 0) (at 0 1.27 0)
      (effects (font (size 1.27 1.27)) hide)
    )
  )
  (global_label "DSI1_LN0_P" (shape input) (at 36.83 159.385 180) (fields_autoplaced)
    (effects (font (size 1.27 1.27)) (justify right))
    (property "Intersheet References" "${INTERSHEET_REFS}" (id 0) (at 0 1.27 0)
      (effects (font (size 1.27 1.27)) hide)
    )
  )
  (global_label "I2S1_DATA0" (shape input) (at 90.17 267.335 180) (fields_autoplaced)
    (effects (font (size 1.27 1.27)) (justify right))
    (property "Intersheet References" "${INTERSHEET_REFS}" (id 0) (at 0 0 0)
      (effects (font (size 1.27 1.27)) hide)
    )
  )
  (global_label "LT9611_GPIO5" (shape input) (at 163.195 246.38 180) (fields_autoplaced)
    (effects (font (size 1.27 1.27)) (justify right))
    (property "Intersheet References" "${INTERSHEET_REFS}" (id 0) (at -1.27 0 0)
      (effects (font (size 1.27 1.27)) hide)
    )
  )
  (global_label "I2C4_SCL" (shape input) (at 265.43 237.49 180) (fields_autoplaced)
    (effects (font (size 1.27 1.27)) (justify right))
    (property "Intersheet References" "${INTERSHEET_REFS}" (id 0) (at 0 0 0)
      (effects (font (size 1.27 1.27)) hide)
    )
  )
  (global_label "I2S1_MCLK" (shape input) (at 90.17 262.255 180) (fields_autoplaced)
    (effects (font (size 1.27 1.27)) (justify right))
    (property "Intersheet References" "${INTERSHEET_REFS}" (id 0) (at 0 0 0)
      (effects (font (size 1.27 1.27)) hide)
    )
  )
  (global_label "I2S1_SCK" (shape input) (at 90.17 257.175 180) (fields_autoplaced)
    (effects (font (size 1.27 1.27)) (justify right))
    (property "Intersheet References" "${INTERSHEET_REFS}" (id 0) (at 0 0 0)
      (effects (font (size 1.27 1.27)) hide)
    )
  )
  (global_label "1V2_SYS" (shape input) (at 23.495 55.245 180) (fields_autoplaced)
    (effects (font (size 1.27 1.27)) (justify right))
    (property "Intersheet References" "${INTERSHEET_REFS}" (id 0) (at 0 0 0)
      (effects (font (size 1.27 1.27)) hide)
    )
  )
  (global_label "5V_SYS" (shape input) (at 222.25 74.295 180) (fields_autoplaced)
    (effects (font (size 1.27 1.27)) (justify right))
    (property "Intersheet References" "${INTERSHEET_REFS}" (id 0) (at 0 10.16 0)
      (effects (font (size 1.27 1.27)) hide)
    )
  )
  (global_label "3V3_SYS" (shape input) (at 327.152 212.09 180) (fields_autoplaced)
    (effects (font (size 1.27 1.27)) (justify right))
    (property "Intersheet References" "${INTERSHEET_REFS}" (id 0) (at 2.032 1.27 0)
      (effects (font (size 1.27 1.27)) hide)
    )
  )
  (global_label "3V3_SYS" (shape input) (at 128.27 231.775 180) (fields_autoplaced)
    (effects (font (size 1.27 1.27)) (justify right))
    (property "Intersheet References" "${INTERSHEET_REFS}" (id 0) (at 0 0 0)
      (effects (font (size 1.27 1.27)) hide)
    )
  )
  (global_label "DSI1_LN1_N" (shape input) (at 36.83 151.765 180) (fields_autoplaced)
    (effects (font (size 1.27 1.27)) (justify right))
    (property "Intersheet References" "${INTERSHEET_REFS}" (id 0) (at 0 1.27 0)
      (effects (font (size 1.27 1.27)) hide)
    )
  )
  (global_label "DSI1_LN2_P" (shape input) (at 36.83 144.145 180) (fields_autoplaced)
    (effects (font (size 1.27 1.27)) (justify right))
    (property "Intersheet References" "${INTERSHEET_REFS}" (id 0) (at 0 1.27 0)
      (effects (font (size 1.27 1.27)) hide)
    )
  )
  (global_label "DSI1_LN2_N" (shape input) (at 36.83 141.605 180) (fields_autoplaced)
    (effects (font (size 1.27 1.27)) (justify right))
    (property "Intersheet References" "${INTERSHEET_REFS}" (id 0) (at 0 1.27 0)
      (effects (font (size 1.27 1.27)) hide)
    )
  )
  (global_label "3V3_SYS" (shape input) (at 40.64 187.325 180) (fields_autoplaced)
    (effects (font (size 1.27 1.27)) (justify right))
    (property "Intersheet References" "${INTERSHEET_REFS}" (id 0) (at 0 0 0)
      (effects (font (size 1.27 1.27)) hide)
    )
  )
  (global_label "I2C4_SDA" (shape bidirectional) (at 265.43 240.03 180) (fields_autoplaced)
    (effects (font (size 1.27 1.27)) (justify right))
    (property "Intersheet References" "${INTERSHEET_REFS}" (id 0) (at 0 0 0)
      (effects (font (size 1.27 1.27)) hide)
    )
  )
  (global_label "I2S1_WS" (shape input) (at 90.17 252.095 180) (fields_autoplaced)
    (effects (font (size 1.27 1.27)) (justify right))
    (property "Intersheet References" "${INTERSHEET_REFS}" (id 0) (at 0 0 0)
      (effects (font (size 1.27 1.27)) hide)
    )
  )
  (global_label "DSI1_LN1_P" (shape input) (at 36.83 154.305 180) (fields_autoplaced)
    (effects (font (size 1.27 1.27)) (justify right))
    (property "Intersheet References" "${INTERSHEET_REFS}" (id 0) (at 0 1.27 0)
      (effects (font (size 1.27 1.27)) hide)
    )
  )
  (global_label "5V_SYS" (shape input) (at 165.735 113.665 180) (fields_autoplaced)
    (effects (font (size 1.27 1.27)) (justify right))
    (property "Intersheet References" "${INTERSHEET_REFS}" (id 0) (at 0 0 0)
      (effects (font (size 1.27 1.27)) hide)
    )
  )
  (global_label "3V3_SYS" (shape input) (at 40.64 109.855 180) (fields_autoplaced)
    (effects (font (size 1.27 1.27)) (justify right))
    (property "Intersheet References" "${INTERSHEET_REFS}" (id 0) (at 0 0 0)
      (effects (font (size 1.27 1.27)) hide)
    )
  )
  (global_label "3V3_SYS" (shape input) (at 215.265 235.585 180) (fields_autoplaced)
    (effects (font (size 1.27 1.27)) (justify right))
    (property "Intersheet References" "${INTERSHEET_REFS}" (id 0) (at -1.27 0 0)
      (effects (font (size 1.27 1.27)) hide)
    )
  )
  (global_label "VREG_S4A_1V8" (shape input) (at 90.17 239.395 180) (fields_autoplaced)
    (effects (font (size 1.27 1.27)) (justify right))
    (property "Intersheet References" "${INTERSHEET_REFS}" (id 0) (at 0 0 0)
      (effects (font (size 1.27 1.27)) hide)
    )
  )
  (global_label "3V3_SYS" (shape input) (at 116.713 247.015 0) (fields_autoplaced)
    (effects (font (size 1.27 1.27)) (justify left))
    (property "Intersheet References" "${INTERSHEET_REFS}" (id 0) (at 206.883 481.965 0)
      (effects (font (size 1.27 1.27)) hide)
    )
  )
  (global_label "LT9611_RST" (shape input) (at 163.195 267.335 180) (fields_autoplaced)
    (effects (font (size 1.27 1.27)) (justify right))
    (property "Intersheet References" "${INTERSHEET_REFS}" (id 0) (at -1.27 0 0)
      (effects (font (size 1.27 1.27)) hide)
    )
  )
  (global_label "3V3_SYS" (shape input) (at 23.495 31.115 180) (fields_autoplaced)
    (effects (font (size 1.27 1.27)) (justify right))
    (property "Intersheet References" "${INTERSHEET_REFS}" (id 0) (at 0 0 0)
      (effects (font (size 1.27 1.27)) hide)
    )
  )
  (global_label "VREG_S4A_1V8" (shape input) (at 167.005 257.175 180) (fields_autoplaced)
    (effects (font (size 1.27 1.27)) (justify right))
    (property "Intersheet References" "${INTERSHEET_REFS}" (id 0) (at -1.27 0 0)
      (effects (font (size 1.27 1.27)) hide)
    )
  )
  (global_label "3V3_SYS" (shape input) (at 183.515 257.175 0) (fields_autoplaced)
    (effects (font (size 1.27 1.27)) (justify left))
    (property "Intersheet References" "${INTERSHEET_REFS}" (id 0) (at 0 0 0)
      (effects (font (size 1.27 1.27)) hide)
    )
  )
  (global_label "VREG_S4A_1V8" (shape input) (at 241.935 227.33 180) (fields_autoplaced)
    (effects (font (size 1.27 1.27)) (justify right))
    (property "Intersheet References" "${INTERSHEET_REFS}" (id 0) (at 0 0 0)
      (effects (font (size 1.27 1.27)) hide)
    )
  )
  (global_label "VREG_S4A_1V8" (shape input) (at 167.005 236.22 180) (fields_autoplaced)
    (effects (font (size 1.27 1.27)) (justify right))
    (property "Intersheet References" "${INTERSHEET_REFS}" (id 0) (at -1.27 0 0)
      (effects (font (size 1.27 1.27)) hide)
    )
  )
  (global_label "3V3_SYS" (shape input) (at 346.075 227.33 0) (fields_autoplaced)
    (effects (font (size 1.27 1.27)) (justify left))
    (property "Intersheet References" "${INTERSHEET_REFS}" (id 0) (at 0 0 0)
      (effects (font (size 1.27 1.27)) hide)
    )
  )
  (global_label "DSI1_CLK_N" (shape input) (at 36.83 146.685 180) (fields_autoplaced)
    (effects (font (size 1.27 1.27)) (justify right))
    (property "Intersheet References" "${INTERSHEET_REFS}" (id 0) (at 0 1.27 0)
      (effects (font (size 1.27 1.27)) hide)
    )
  )

  (symbol (lib_id "sa800u-baseboard-hw:C_1u_0402") (at 185.42 268.605 270) (unit 1)
    (in_bom yes) (on_board yes) (fields_autoplaced)
    (property "Reference" "C34" (id 0) (at 188.976 269.8813 90)
      (effects (font (size 1.524 1.524)) (justify left))
    )
    (property "Value" "C_1u_0402" (id 1) (at 181.61 268.605 0)
      (effects (font (size 1.524 1.524)) hide)
    )
    (property "Footprint" "sa800u-baseboard-hw-footprints:C_0402_1005Metric" (id 2) (at 190.5 273.685 0)
      (effects (font (size 1.524 1.524)) (justify left) hide)
    )
    (property "Datasheet" " " (id 3) (at 185.42 268.605 0)
      (effects (font (size 1.27 1.27)) hide)
    )
    (property "Manufacturer" "TDK" (id 4) (at 195.58 273.685 0)
      (effects (font (size 1.524 1.524)) (justify left) hide)
    )
    (property "MPN" "C1005X6S1A105K050BC" (id 5) (at 193.04 273.685 0)
      (effects (font (size 1.524 1.524)) (justify left) hide)
    )
    (property "Val" "1u" (id 6) (at 188.976 273.0562 90)
      (effects (font (size 1.27 1.27)) (justify left))
    )
    (property "License" "Apache-2.0" (id 7) (at 162.56 288.925 0)
      (effects (font (size 1.27 1.27) (thickness 0.15)) (justify left bottom) hide)
    )
    (property "Author" "Antmicro" (id 8) (at 160.02 288.925 0)
      (effects (font (size 1.27 1.27) (thickness 0.15)) (justify left bottom) hide)
    )
    (property "Voltage" "" (id 9) (at 157.48 288.925 0)
      (effects (font (size 1.27 1.27)) (justify left bottom) hide)
    )
    (property "Dielectric" "" (id 10) (at 154.94 288.925 0)
      (effects (font (size 1.27 1.27)) (justify left bottom) hide)
    )
    (pin "1")
    (pin "2")
  )

  (symbol (lib_id "sa800u-baseboard-hw:GND") (at 185.42 273.685 0) (unit 1)
    (in_bom yes) (on_board yes) (fields_autoplaced)
    (property "Reference" "#PWR023" (id 0) (at 185.42 280.035 0)
      (effects (font (size 1.27 1.27)) hide)
    )
    (property "Value" "GND" (id 1) (at 185.42 278.13 0))
    (property "Footprint" "" (id 2) (at 185.42 273.685 0)
      (effects (font (size 1.27 1.27)) hide)
    )
    (property "Datasheet" "" (id 3) (at 185.42 273.685 0)
      (effects (font (size 1.27 1.27)) hide)
    )
    (property "Author" "Antmicro" (id 4) (at 194.31 281.305 0)
      (effects (font (size 1.27 1.27) (thickness 0.15)) (justify left bottom) hide)
    )
    (property "License" "Apache-2.0" (id 5) (at 194.31 283.845 0)
      (effects (font (size 1.27 1.27) (thickness 0.15)) (justify left bottom) hide)
    )
    (pin "1")
  )

  (symbol (lib_id "sa800u-baseboard-hw:R_4k7_0402") (at 66.675 111.125 270) (unit 1)
    (in_bom yes) (on_board yes) (fields_autoplaced)
    (property "Reference" "R20" (id 0) (at 68.58 112.395 90)
      (effects (font (size 1.524 1.524)) (justify left))
    )
    (property "Value" "R_4k7_0402" (id 1) (at 62.865 111.125 0)
      (effects (font (size 1.524 1.524)) hide)
    )
    (property "Footprint" "sa800u-baseboard-hw-footprints:R_0402_1005Metric" (id 2) (at 71.755 116.205 0)
      (effects (font (size 1.524 1.524)) (justify left) hide)
    )
    (property "Datasheet" "https://www.bourns.com/docs/product-datasheets/cr.pdf" (id 3) (at 66.675 111.125 0)
      (effects (font (size 1.27 1.27)) hide)
    )
    (property "Manufacturer" "Bourns" (id 4) (at 76.835 116.205 0)
      (effects (font (size 1.524 1.524)) (justify left) hide)
    )
    (property "MPN" "CR0402-FX-4701GLF" (id 5) (at 74.295 116.205 0)
      (effects (font (size 1.524 1.524)) (justify left) hide)
    )
    (property "Val" "4k7" (id 6) (at 68.58 115.5699 90)
      (effects (font (size 1.27 1.27)) (justify left))
    )
    (property "License" "Apache-2.0" (id 7) (at 41.275 131.445 0)
      (effects (font (size 1.27 1.27) (thickness 0.15)) (justify left bottom) hide)
    )
    (property "Author" "Antmicro" (id 8) (at 38.735 131.445 0)
      (effects (font (size 1.27 1.27) (thickness 0.15)) (justify left bottom) hide)
    )
    (property "Tolerance" "1%" (id 9) (at 56.515 131.445 0)
      (effects (font (size 1.27 1.27)) (justify left bottom) hide)
    )
    (pin "1")
    (pin "2")
  )

  (symbol (lib_id "sa800u-baseboard-hw:R_4k7_0402") (at 58.42 111.125 270) (unit 1)
    (in_bom yes) (on_board yes) (fields_autoplaced)
    (property "Reference" "R19" (id 0) (at 60.96 112.395 90)
      (effects (font (size 1.524 1.524)) (justify left))
    )
    (property "Value" "R_4k7_0402" (id 1) (at 54.61 111.125 0)
      (effects (font (size 1.524 1.524)) hide)
    )
    (property "Footprint" "sa800u-baseboard-hw-footprints:R_0402_1005Metric" (id 2) (at 63.5 116.205 0)
      (effects (font (size 1.524 1.524)) (justify left) hide)
    )
    (property "Datasheet" "https://www.bourns.com/docs/product-datasheets/cr.pdf" (id 3) (at 58.42 111.125 0)
      (effects (font (size 1.27 1.27)) hide)
    )
    (property "Manufacturer" "Bourns" (id 4) (at 68.58 116.205 0)
      (effects (font (size 1.524 1.524)) (justify left) hide)
    )
    (property "MPN" "CR0402-FX-4701GLF" (id 5) (at 66.04 116.205 0)
      (effects (font (size 1.524 1.524)) (justify left) hide)
    )
    (property "Val" "4k7" (id 6) (at 60.96 115.5699 90)
      (effects (font (size 1.27 1.27)) (justify left))
    )
    (property "License" "Apache-2.0" (id 7) (at 33.02 131.445 0)
      (effects (font (size 1.27 1.27) (thickness 0.15)) (justify left bottom) hide)
    )
    (property "Author" "Antmicro" (id 8) (at 30.48 131.445 0)
      (effects (font (size 1.27 1.27) (thickness 0.15)) (justify left bottom) hide)
    )
    (property "Tolerance" "1%" (id 9) (at 48.26 131.445 0)
      (effects (font (size 1.27 1.27)) (justify left bottom) hide)
    )
    (pin "1")
    (pin "2")
  )

  (symbol (lib_id "sa800u-baseboard-hw:R_4k7_0402") (at 50.8 111.125 270) (unit 1)
    (in_bom yes) (on_board yes) (fields_autoplaced)
    (property "Reference" "R18" (id 0) (at 53.34 112.395 90)
      (effects (font (size 1.524 1.524)) (justify left))
    )
    (property "Value" "R_4k7_0402" (id 1) (at 46.99 111.125 0)
      (effects (font (size 1.524 1.524)) hide)
    )
    (property "Footprint" "sa800u-baseboard-hw-footprints:R_0402_1005Metric" (id 2) (at 55.88 116.205 0)
      (effects (font (size 1.524 1.524)) (justify left) hide)
    )
    (property "Datasheet" "https://www.bourns.com/docs/product-datasheets/cr.pdf" (id 3) (at 50.8 111.125 0)
      (effects (font (size 1.27 1.27)) hide)
    )
    (property "Manufacturer" "Bourns" (id 4) (at 60.96 116.205 0)
      (effects (font (size 1.524 1.524)) (justify left) hide)
    )
    (property "MPN" "CR0402-FX-4701GLF" (id 5) (at 58.42 116.205 0)
      (effects (font (size 1.524 1.524)) (justify left) hide)
    )
    (property "Val" "4k7" (id 6) (at 53.34 115.5699 90)
      (effects (font (size 1.27 1.27)) (justify left))
    )
    (property "License" "Apache-2.0" (id 7) (at 25.4 131.445 0)
      (effects (font (size 1.27 1.27) (thickness 0.15)) (justify left bottom) hide)
    )
    (property "Author" "Antmicro" (id 8) (at 22.86 131.445 0)
      (effects (font (size 1.27 1.27) (thickness 0.15)) (justify left bottom) hide)
    )
    (property "Tolerance" "1%" (id 9) (at 40.64 131.445 0)
      (effects (font (size 1.27 1.27)) (justify left bottom) hide)
    )
    (pin "1")
    (pin "2")
  )

  (symbol (lib_id "sa800u-baseboard-hw:R_1k_0402") (at 41.91 191.262 270) (unit 1)
    (in_bom yes) (on_board yes) (fields_autoplaced)
    (property "Reference" "R15" (id 0) (at 44.45 191.262 90)
      (effects (font (size 1.524 1.524)) (justify left))
    )
    (property "Value" "R_1k_0402" (id 1) (at 38.1 191.262 0)
      (effects (font (size 1.524 1.524)) hide)
    )
    (property "Footprint" "sa800u-baseboard-hw-footprints:R_0402_1005Metric" (id 2) (at 46.99 196.342 0)
      (effects (font (size 1.524 1.524)) (justify left) hide)
    )
    (property "Datasheet" "https://www.bourns.com/docs/product-datasheets/cr.pdf" (id 3) (at 41.91 191.262 0)
      (effects (font (size 1.27 1.27)) hide)
    )
    (property "Manufacturer" "Bourns" (id 4) (at 52.07 196.342 0)
      (effects (font (size 1.524 1.524)) (justify left) hide)
    )
    (property "MPN" "CR0402-FX-1001GLF" (id 5) (at 49.53 196.342 0)
      (effects (font (size 1.524 1.524)) (justify left) hide)
    )
    (property "Val" "1k" (id 6) (at 44.45 194.4369 90)
      (effects (font (size 1.27 1.27)) (justify left))
    )
    (property "DNP" "DNP" (id 7) (at 44.45 196.9769 90)
      (effects (font (size 1.27 1.27)) (justify left))
    )
    (property "License" "Apache-2.0" (id 8) (at 16.51 211.582 0)
      (effects (font (size 1.27 1.27) (thickness 0.15)) (justify left bottom) hide)
    )
    (property "Author" "Antmicro" (id 9) (at 13.97 211.582 0)
      (effects (font (size 1.27 1.27) (thickness 0.15)) (justify left bottom) hide)
    )
    (property "Tolerance" "1%" (id 10) (at 31.75 211.582 0)
      (effects (font (size 1.27 1.27)) (justify left bottom) hide)
    )
    (pin "1")
    (pin "2")
  )

  (symbol (lib_id "sa800u-baseboard-hw:R_0R_0402") (at 41.91 201.422 270) (unit 1)
    (in_bom yes) (on_board yes) (fields_autoplaced)
    (property "Reference" "R16" (id 0) (at 44.45 202.692 90)
      (effects (font (size 1.524 1.524)) (justify left))
    )
    (property "Value" "R_0R_0402" (id 1) (at 38.1 201.422 0)
      (effects (font (size 1.524 1.524)) hide)
    )
    (property "Footprint" "sa800u-baseboard-hw-footprints:R_0402_1005Metric" (id 2) (at 46.99 206.502 0)
      (effects (font (size 1.524 1.524)) (justify left) hide)
    )
    (property "Datasheet" "https://industrial.panasonic.com/cdbs/www-data/pdf/RDA0000/AOA0000C301.pdf" (id 3) (at 41.91 201.422 0)
      (effects (font (size 1.27 1.27)) hide)
    )
    (property "Manufacturer" "Panasonic" (id 4) (at 52.07 206.502 0)
      (effects (font (size 1.524 1.524)) (justify left) hide)
    )
    (property "MPN" "ERJ2GE0R00X" (id 5) (at 49.53 206.502 0)
      (effects (font (size 1.524 1.524)) (justify left) hide)
    )
    (property "Val" "0R" (id 6) (at 44.45 205.8669 90)
      (effects (font (size 1.27 1.27)) (justify left))
    )
    (property "License" "Apache-2.0" (id 7) (at 16.51 221.742 0)
      (effects (font (size 1.27 1.27) (thickness 0.15)) (justify left bottom) hide)
    )
    (property "Author" "Antmicro" (id 8) (at 13.97 221.742 0)
      (effects (font (size 1.27 1.27) (thickness 0.15)) (justify left bottom) hide)
    )
    (property "Tolerance" "~" (id 9) (at 31.75 221.742 0)
      (effects (font (size 1.27 1.27)) (justify left bottom) hide)
    )
    (property "Current" "1A" (id 10) (at 11.43 221.742 0)
      (effects (font (size 1.27 1.27) (thickness 0.15)) (justify left bottom) hide)
    )
    (pin "1")
    (pin "2")
  )

  (symbol (lib_id "sa800u-baseboard-hw:GND") (at 41.91 206.375 0) (unit 1)
    (in_bom yes) (on_board yes) (fields_autoplaced)
    (property "Reference" "#PWR012" (id 0) (at 41.91 212.725 0)
      (effects (font (size 1.27 1.27)) hide)
    )
    (property "Value" "GND" (id 1) (at 41.91 210.82 0))
    (property "Footprint" "" (id 2) (at 41.91 206.375 0)
      (effects (font (size 1.27 1.27)) hide)
    )
    (property "Datasheet" "" (id 3) (at 41.91 206.375 0)
      (effects (font (size 1.27 1.27)) hide)
    )
    (property "Author" "Antmicro" (id 4) (at 50.8 213.995 0)
      (effects (font (size 1.27 1.27) (thickness 0.15)) (justify left bottom) hide)
    )
    (property "License" "Apache-2.0" (id 5) (at 50.8 216.535 0)
      (effects (font (size 1.27 1.27) (thickness 0.15)) (justify left bottom) hide)
    )
    (pin "1")
  )

  (symbol (lib_id "sa800u-baseboard-hw:R_2k2_0402") (at 167.005 115.697 270) (unit 1)
    (in_bom yes) (on_board yes) (fields_autoplaced)
    (property "Reference" "R28" (id 0) (at 168.91 116.967 90)
      (effects (font (size 1.524 1.524)) (justify left))
    )
    (property "Value" "R_2k2_0402" (id 1) (at 163.195 115.697 0)
      (effects (font (size 1.524 1.524)) hide)
    )
    (property "Footprint" "sa800u-baseboard-hw-footprints:R_0402_1005Metric" (id 2) (at 172.085 120.777 0)
      (effects (font (size 1.524 1.524)) (justify left) hide)
    )
    (property "Datasheet" "https://www.bourns.com/docs/product-datasheets/cr.pdf" (id 3) (at 167.005 115.697 0)
      (effects (font (size 1.27 1.27)) hide)
    )
    (property "Manufacturer" "Bourns" (id 4) (at 177.165 120.777 0)
      (effects (font (size 1.524 1.524)) (justify left) hide)
    )
    (property "MPN" "CR0402-FX-2201GLF" (id 5) (at 174.625 120.777 0)
      (effects (font (size 1.524 1.524)) (justify left) hide)
    )
    (property "Val" "2k2" (id 6) (at 168.91 120.1419 90)
      (effects (font (size 1.27 1.27)) (justify left))
    )
    (property "License" "Apache-2.0" (id 7) (at 141.605 136.017 0)
      (effects (font (size 1.27 1.27) (thickness 0.15)) (justify left bottom) hide)
    )
    (property "Author" "Antmicro" (id 8) (at 139.065 136.017 0)
      (effects (font (size 1.27 1.27) (thickness 0.15)) (justify left bottom) hide)
    )
    (property "Tolerance" "1%" (id 9) (at 156.845 136.017 0)
      (effects (font (size 1.27 1.27)) (justify left bottom) hide)
    )
    (pin "1")
    (pin "2")
  )

  (symbol (lib_id "sa800u-baseboard-hw:R_2k2_0402") (at 174.625 115.697 270) (unit 1)
    (in_bom yes) (on_board yes) (fields_autoplaced)
    (property "Reference" "R32" (id 0) (at 176.53 116.967 90)
      (effects (font (size 1.524 1.524)) (justify left))
    )
    (property "Value" "R_2k2_0402" (id 1) (at 170.815 115.697 0)
      (effects (font (size 1.524 1.524)) hide)
    )
    (property "Footprint" "sa800u-baseboard-hw-footprints:R_0402_1005Metric" (id 2) (at 179.705 120.777 0)
      (effects (font (size 1.524 1.524)) (justify left) hide)
    )
    (property "Datasheet" "https://www.bourns.com/docs/product-datasheets/cr.pdf" (id 3) (at 174.625 115.697 0)
      (effects (font (size 1.27 1.27)) hide)
    )
    (property "Manufacturer" "Bourns" (id 4) (at 184.785 120.777 0)
      (effects (font (size 1.524 1.524)) (justify left) hide)
    )
    (property "MPN" "CR0402-FX-2201GLF" (id 5) (at 182.245 120.777 0)
      (effects (font (size 1.524 1.524)) (justify left) hide)
    )
    (property "Val" "2k2" (id 6) (at 176.53 120.1419 90)
      (effects (font (size 1.27 1.27)) (justify left))
    )
    (property "License" "Apache-2.0" (id 7) (at 149.225 136.017 0)
      (effects (font (size 1.27 1.27) (thickness 0.15)) (justify left bottom) hide)
    )
    (property "Author" "Antmicro" (id 8) (at 146.685 136.017 0)
      (effects (font (size 1.27 1.27) (thickness 0.15)) (justify left bottom) hide)
    )
    (property "Tolerance" "1%" (id 9) (at 164.465 136.017 0)
      (effects (font (size 1.27 1.27)) (justify left bottom) hide)
    )
    (pin "1")
    (pin "2")
  )

  (symbol (lib_id "sa800u-baseboard-hw:R_0R_0402") (at 167.64 155.575 0) (unit 1)
    (in_bom yes) (on_board yes) (fields_autoplaced)
    (property "Reference" "R30" (id 0) (at 170.18 160.02 0)
      (effects (font (size 1.524 1.524)))
    )
    (property "Value" "R_0R_0402" (id 1) (at 167.64 159.385 0)
      (effects (font (size 1.524 1.524)) hide)
    )
    (property "Footprint" "sa800u-baseboard-hw-footprints:R_0402_1005Metric" (id 2) (at 172.72 150.495 0)
      (effects (font (size 1.524 1.524)) (justify left) hide)
    )
    (property "Datasheet" "https://industrial.panasonic.com/cdbs/www-data/pdf/RDA0000/AOA0000C301.pdf" (id 3) (at 167.64 155.575 0)
      (effects (font (size 1.27 1.27)) hide)
    )
    (property "Manufacturer" "Panasonic" (id 4) (at 172.72 145.415 0)
      (effects (font (size 1.524 1.524)) (justify left) hide)
    )
    (property "MPN" "ERJ2GE0R00X" (id 5) (at 172.72 147.955 0)
      (effects (font (size 1.524 1.524)) (justify left) hide)
    )
    (property "Val" "0R" (id 6) (at 170.18 162.56 0))
    (property "License" "Apache-2.0" (id 7) (at 187.96 180.975 0)
      (effects (font (size 1.27 1.27) (thickness 0.15)) (justify left bottom) hide)
    )
    (property "Author" "Antmicro" (id 8) (at 187.96 183.515 0)
      (effects (font (size 1.27 1.27) (thickness 0.15)) (justify left bottom) hide)
    )
    (property "Tolerance" "~" (id 9) (at 187.96 165.735 0)
      (effects (font (size 1.27 1.27)) (justify left bottom) hide)
    )
    (property "Current" "1A" (id 10) (at 187.96 186.055 0)
      (effects (font (size 1.27 1.27) (thickness 0.15)) (justify left bottom) hide)
    )
    (pin "1")
    (pin "2")
  )

  (symbol (lib_id "sa800u-baseboard-hw:R_20k_0402") (at 160.401 158.115 270) (unit 1)
    (in_bom yes) (on_board yes) (fields_autoplaced)
    (property "Reference" "R27" (id 0) (at 162.941 159.385 90)
      (effects (font (size 1.524 1.524)) (justify left))
    )
    (property "Value" "R_20k_0402" (id 1) (at 156.591 158.115 0)
      (effects (font (size 1.524 1.524)) hide)
    )
    (property "Footprint" "sa800u-baseboard-hw-footprints:R_0402_1005Metric" (id 2) (at 165.481 163.195 0)
      (effects (font (size 1.524 1.524)) (justify left) hide)
    )
    (property "Datasheet" "https://www.bourns.com/docs/product-datasheets/cr.pdf" (id 3) (at 160.401 158.115 0)
      (effects (font (size 1.27 1.27)) hide)
    )
    (property "Manufacturer" "Bourns" (id 4) (at 170.561 163.195 0)
      (effects (font (size 1.524 1.524)) (justify left) hide)
    )
    (property "MPN" "CR0402-FX-2002GLF" (id 5) (at 168.021 163.195 0)
      (effects (font (size 1.524 1.524)) (justify left) hide)
    )
    (property "Val" "20k" (id 6) (at 162.941 162.5599 90)
      (effects (font (size 1.27 1.27)) (justify left))
    )
    (property "License" "Apache-2.0" (id 7) (at 135.001 178.435 0)
      (effects (font (size 1.27 1.27) (thickness 0.15)) (justify left bottom) hide)
    )
    (property "Author" "Antmicro" (id 8) (at 132.461 178.435 0)
      (effects (font (size 1.27 1.27) (thickness 0.15)) (justify left bottom) hide)
    )
    (property "Tolerance" "1%" (id 9) (at 150.241 178.435 0)
      (effects (font (size 1.27 1.27)) (justify left bottom) hide)
    )
    (pin "1")
    (pin "2")
  )

  (symbol (lib_id "sa800u-baseboard-hw:GND") (at 160.401 163.195 0) (unit 1)
    (in_bom yes) (on_board yes) (fields_autoplaced)
    (property "Reference" "#PWR026" (id 0) (at 160.401 169.545 0)
      (effects (font (size 1.27 1.27)) hide)
    )
    (property "Value" "GND" (id 1) (at 160.401 167.64 0))
    (property "Footprint" "" (id 2) (at 160.401 163.195 0)
      (effects (font (size 1.27 1.27)) hide)
    )
    (property "Datasheet" "" (id 3) (at 160.401 163.195 0)
      (effects (font (size 1.27 1.27)) hide)
    )
    (property "Author" "Antmicro" (id 4) (at 169.291 170.815 0)
      (effects (font (size 1.27 1.27) (thickness 0.15)) (justify left bottom) hide)
    )
    (property "License" "Apache-2.0" (id 5) (at 169.291 173.355 0)
      (effects (font (size 1.27 1.27) (thickness 0.15)) (justify left bottom) hide)
    )
    (pin "1")
  )

  (symbol (lib_id "sa800u-baseboard-hw:GND") (at 91.821 210.312 0) (unit 1)
    (in_bom yes) (on_board yes) (fields_autoplaced)
    (property "Reference" "#PWR019" (id 0) (at 91.821 216.662 0)
      (effects (font (size 1.27 1.27)) hide)
    )
    (property "Value" "GND" (id 1) (at 91.821 214.757 0))
    (property "Footprint" "" (id 2) (at 91.821 210.312 0)
      (effects (font (size 1.27 1.27)) hide)
    )
    (property "Datasheet" "" (id 3) (at 91.821 210.312 0)
      (effects (font (size 1.27 1.27)) hide)
    )
    (property "Author" "Antmicro" (id 4) (at 100.711 217.932 0)
      (effects (font (size 1.27 1.27) (thickness 0.15)) (justify left bottom) hide)
    )
    (property "License" "Apache-2.0" (id 5) (at 100.711 220.472 0)
      (effects (font (size 1.27 1.27) (thickness 0.15)) (justify left bottom) hide)
    )
    (pin "1")
  )

  (symbol (lib_id "sa800u-baseboard-hw:TXB0104_UQFN") (at 93.98 247.015 0) (unit 1)
    (in_bom yes) (on_board yes) (fields_autoplaced)
    (property "Reference" "U2" (id 0) (at 104.14 238.76 0))
    (property "Value" "TXB0104_UQFN" (id 1) (at 104.14 280.67 0)
      (effects (font (size 1.27 1.27)) hide)
    )
    (property "Footprint" "sa800u-baseboard-hw-footprints:UQFN-12_2x1.7mm_P0.4mm_Texas_RUT" (id 2) (at 91.44 269.875 0)
      (effects (font (size 1.27 1.27)) hide)
    )
    (property "Datasheet" "http://www.ti.com/lit/ds/symlink/txb0104.pdf" (id 3) (at 96.774 244.602 0)
      (effects (font (size 1.27 1.27)) hide)
    )
    (property "Manufacturer" "Texas Instruments" (id 4) (at 83.82 268.605 0)
      (effects (font (size 1.27 1.27)) hide)
    )
    (property "MPN" "TXB0104RUTR" (id 5) (at 104.14 241.3 0))
    (property "Author" "Antmicro" (id 6) (at 129.54 267.335 0)
      (effects (font (size 1.27 1.27) (thickness 0.15)) (justify left bottom) hide)
    )
    (property "License" "Apache-2.0" (id 7) (at 129.54 269.875 0)
      (effects (font (size 1.27 1.27) (thickness 0.15)) (justify left bottom) hide)
    )
    (pin "1")
    (pin "10")
    (pin "11")
    (pin "12")
    (pin "2")
    (pin "3")
    (pin "4")
    (pin "5")
    (pin "6")
    (pin "7")
    (pin "8")
    (pin "9")
  )

  (symbol (lib_id "sa800u-baseboard-hw:C_100n_0402") (at 134.62 238.76 270) (unit 1)
    (in_bom yes) (on_board yes) (fields_autoplaced)
    (property "Reference" "C20" (id 0) (at 137.414 240.0363 90)
      (effects (font (size 1.524 1.524)) (justify left))
    )
    (property "Value" "C_100n_0402" (id 1) (at 130.81 238.76 0)
      (effects (font (size 1.524 1.524)) hide)
    )
    (property "Footprint" "sa800u-baseboard-hw-footprints:C_0402_1005Metric" (id 2) (at 139.7 243.84 0)
      (effects (font (size 1.524 1.524)) (justify left) hide)
    )
    (property "Datasheet" "https://search.murata.co.jp/Ceramy/image/img/A01X/G101/ENG/GRM155R61H104KE14-01.pdf" (id 3) (at 134.62 238.76 0)
      (effects (font (size 1.27 1.27)) hide)
    )
    (property "Manufacturer" "Murata" (id 4) (at 144.78 243.84 0)
      (effects (font (size 1.524 1.524)) (justify left) hide)
    )
    (property "MPN" "GRM155R61H104KE14D" (id 5) (at 142.24 243.84 0)
      (effects (font (size 1.524 1.524)) (justify left) hide)
    )
    (property "Val" "100n" (id 6) (at 137.414 243.2112 90)
      (effects (font (size 1.27 1.27)) (justify left))
    )
    (property "License" "Apache-2.0" (id 7) (at 111.76 259.08 0)
      (effects (font (size 1.27 1.27) (thickness 0.15)) (justify left bottom) hide)
    )
    (property "Author" "Antmicro" (id 8) (at 109.22 259.08 0)
      (effects (font (size 1.27 1.27) (thickness 0.15)) (justify left bottom) hide)
    )
    (property "Voltage" "50V" (id 9) (at 106.68 259.08 0)
      (effects (font (size 1.27 1.27)) (justify left bottom) hide)
    )
    (property "Dielectric" "X5R" (id 10) (at 104.14 259.08 0)
      (effects (font (size 1.27 1.27)) (justify left bottom) hide)
    )
    (pin "1")
    (pin "2")
  )

  (symbol (lib_id "sa800u-baseboard-hw:C_100n_0402") (at 129.54 238.76 270) (unit 1)
    (in_bom yes) (on_board yes) (fields_autoplaced)
    (property "Reference" "C18" (id 0) (at 127 240.0363 90)
      (effects (font (size 1.524 1.524)) (justify right))
    )
    (property "Value" "C_100n_0402" (id 1) (at 125.73 238.76 0)
      (effects (font (size 1.524 1.524)) hide)
    )
    (property "Footprint" "sa800u-baseboard-hw-footprints:C_0402_1005Metric" (id 2) (at 134.62 243.84 0)
      (effects (font (size 1.524 1.524)) (justify left) hide)
    )
    (property "Datasheet" "https://search.murata.co.jp/Ceramy/image/img/A01X/G101/ENG/GRM155R61H104KE14-01.pdf" (id 3) (at 129.54 238.76 0)
      (effects (font (size 1.27 1.27)) hide)
    )
    (property "Manufacturer" "Murata" (id 4) (at 139.7 243.84 0)
      (effects (font (size 1.524 1.524)) (justify left) hide)
    )
    (property "MPN" "GRM155R61H104KE14D" (id 5) (at 137.16 243.84 0)
      (effects (font (size 1.524 1.524)) (justify left) hide)
    )
    (property "Val" "100n" (id 6) (at 127 243.2112 90)
      (effects (font (size 1.27 1.27)) (justify right))
    )
    (property "License" "Apache-2.0" (id 7) (at 106.68 259.08 0)
      (effects (font (size 1.27 1.27) (thickness 0.15)) (justify left bottom) hide)
    )
    (property "Author" "Antmicro" (id 8) (at 104.14 259.08 0)
      (effects (font (size 1.27 1.27) (thickness 0.15)) (justify left bottom) hide)
    )
    (property "Voltage" "50V" (id 9) (at 101.6 259.08 0)
      (effects (font (size 1.27 1.27)) (justify left bottom) hide)
    )
    (property "Dielectric" "X5R" (id 10) (at 99.06 259.08 0)
      (effects (font (size 1.27 1.27)) (justify left bottom) hide)
    )
    (pin "1")
    (pin "2")
  )

  (symbol (lib_id "sa800u-baseboard-hw:GND") (at 116.205 273.431 0) (unit 1)
    (in_bom yes) (on_board yes) (fields_autoplaced)
    (property "Reference" "#PWR014" (id 0) (at 116.205 279.781 0)
      (effects (font (size 1.27 1.27)) hide)
    )
    (property "Value" "GND" (id 1) (at 116.205 278.13 0))
    (property "Footprint" "" (id 2) (at 116.205 273.431 0)
      (effects (font (size 1.27 1.27)) hide)
    )
    (property "Datasheet" "" (id 3) (at 116.205 273.431 0)
      (effects (font (size 1.27 1.27)) hide)
    )
    (property "Author" "Antmicro" (id 4) (at 125.095 281.051 0)
      (effects (font (size 1.27 1.27) (thickness 0.15)) (justify left bottom) hide)
    )
    (property "License" "Apache-2.0" (id 5) (at 125.095 283.591 0)
      (effects (font (size 1.27 1.27) (thickness 0.15)) (justify left bottom) hide)
    )
    (pin "1")
  )

  (symbol (lib_id "sa800u-baseboard-hw:R_4k7_0402") (at 168.275 258.953 270) (unit 1)
    (in_bom yes) (on_board yes) (fields_autoplaced)
    (property "Reference" "R24" (id 0) (at 166.37 260.223 90)
      (effects (font (size 1.524 1.524)) (justify right))
    )
    (property "Value" "R_4k7_0402" (id 1) (at 164.465 258.953 0)
      (effects (font (size 1.524 1.524)) hide)
    )
    (property "Footprint" "sa800u-baseboard-hw-footprints:R_0402_1005Metric" (id 2) (at 173.355 264.033 0)
      (effects (font (size 1.524 1.524)) (justify left) hide)
    )
    (property "Datasheet" "https://www.bourns.com/docs/product-datasheets/cr.pdf" (id 3) (at 168.275 258.953 0)
      (effects (font (size 1.27 1.27)) hide)
    )
    (property "Manufacturer" "Bourns" (id 4) (at 178.435 264.033 0)
      (effects (font (size 1.524 1.524)) (justify left) hide)
    )
    (property "MPN" "CR0402-FX-4701GLF" (id 5) (at 175.895 264.033 0)
      (effects (font (size 1.524 1.524)) (justify left) hide)
    )
    (property "Val" "4k7" (id 6) (at 166.37 263.3979 90)
      (effects (font (size 1.27 1.27)) (justify right))
    )
    (property "License" "Apache-2.0" (id 7) (at 142.875 279.273 0)
      (effects (font (size 1.27 1.27) (thickness 0.15)) (justify left bottom) hide)
    )
    (property "Author" "Antmicro" (id 8) (at 140.335 279.273 0)
      (effects (font (size 1.27 1.27) (thickness 0.15)) (justify left bottom) hide)
    )
    (property "Tolerance" "1%" (id 9) (at 158.115 279.273 0)
      (effects (font (size 1.27 1.27)) (justify left bottom) hide)
    )
    (pin "1")
    (pin "2")
  )

  (symbol (lib_id "sa800u-baseboard-hw:R_4k7_0402") (at 182.245 258.953 270) (unit 1)
    (in_bom yes) (on_board yes) (fields_autoplaced)
    (property "Reference" "R26" (id 0) (at 184.15 260.223 90)
      (effects (font (size 1.524 1.524)) (justify left))
    )
    (property "Value" "R_4k7_0402" (id 1) (at 178.435 258.953 0)
      (effects (font (size 1.524 1.524)) hide)
    )
    (property "Footprint" "sa800u-baseboard-hw-footprints:R_0402_1005Metric" (id 2) (at 187.325 264.033 0)
      (effects (font (size 1.524 1.524)) (justify left) hide)
    )
    (property "Datasheet" "https://www.bourns.com/docs/product-datasheets/cr.pdf" (id 3) (at 182.245 258.953 0)
      (effects (font (size 1.27 1.27)) hide)
    )
    (property "Manufacturer" "Bourns" (id 4) (at 192.405 264.033 0)
      (effects (font (size 1.524 1.524)) (justify left) hide)
    )
    (property "MPN" "CR0402-FX-4701GLF" (id 5) (at 189.865 264.033 0)
      (effects (font (size 1.524 1.524)) (justify left) hide)
    )
    (property "Val" "4k7" (id 6) (at 184.15 263.3979 90)
      (effects (font (size 1.27 1.27)) (justify left))
    )
    (property "License" "Apache-2.0" (id 7) (at 156.845 279.273 0)
      (effects (font (size 1.27 1.27) (thickness 0.15)) (justify left bottom) hide)
    )
    (property "Author" "Antmicro" (id 8) (at 154.305 279.273 0)
      (effects (font (size 1.27 1.27) (thickness 0.15)) (justify left bottom) hide)
    )
    (property "Tolerance" "1%" (id 9) (at 172.085 279.273 0)
      (effects (font (size 1.27 1.27)) (justify left bottom) hide)
    )
    (pin "1")
    (pin "2")
  )

  (symbol (lib_id "sa800u-baseboard-hw:R_10k_0402") (at 216.535 240.665 270) (unit 1)
    (in_bom yes) (on_board yes) (fields_autoplaced)
    (property "Reference" "R29" (id 0) (at 218.44 241.935 90)
      (effects (font (size 1.524 1.524)) (justify left))
    )
    (property "Value" "R_10k_0402" (id 1) (at 212.725 240.665 0)
      (effects (font (size 1.524 1.524)) hide)
    )
    (property "Footprint" "sa800u-baseboard-hw-footprints:R_0402_1005Metric" (id 2) (at 221.615 245.745 0)
      (effects (font (size 1.524 1.524)) (justify left) hide)
    )
    (property "Datasheet" "https://www.bourns.com/docs/product-datasheets/cr.pdf" (id 3) (at 216.535 240.665 0)
      (effects (font (size 1.27 1.27)) hide)
    )
    (property "Manufacturer" "Bourns" (id 4) (at 226.695 245.745 0)
      (effects (font (size 1.524 1.524)) (justify left) hide)
    )
    (property "MPN" "CR0402-FX-1002GLF" (id 5) (at 224.155 245.745 0)
      (effects (font (size 1.524 1.524)) (justify left) hide)
    )
    (property "Val" "10k" (id 6) (at 218.44 245.1099 90)
      (effects (font (size 1.27 1.27)) (justify left))
    )
    (property "License" "Apache-2.0" (id 7) (at 191.135 260.985 0)
      (effects (font (size 1.27 1.27) (thickness 0.15)) (justify left bottom) hide)
    )
    (property "Author" "Antmicro" (id 8) (at 188.595 260.985 0)
      (effects (font (size 1.27 1.27) (thickness 0.15)) (justify left bottom) hide)
    )
    (property "Tolerance" "1%" (id 9) (at 206.375 260.985 0)
      (effects (font (size 1.27 1.27)) (justify left bottom) hide)
    )
    (pin "1")
    (pin "2")
  )

  (symbol (lib_id "sa800u-baseboard-hw:R_27k_0402") (at 226.695 248.285 270) (unit 1)
    (in_bom yes) (on_board yes) (fields_autoplaced)
    (property "Reference" "R33" (id 0) (at 228.6 249.555 90)
      (effects (font (size 1.524 1.524)) (justify left))
    )
    (property "Value" "R_27k_0402" (id 1) (at 222.885 248.285 0)
      (effects (font (size 1.524 1.524)) hide)
    )
    (property "Footprint" "sa800u-baseboard-hw-footprints:R_0402_1005Metric" (id 2) (at 231.775 253.365 0)
      (effects (font (size 1.524 1.524)) (justify left) hide)
    )
    (property "Datasheet" "https://www.bourns.com/docs/product-datasheets/cr.pdf" (id 3) (at 226.695 248.285 0)
      (effects (font (size 1.27 1.27)) hide)
    )
    (property "Manufacturer" "Bourns" (id 4) (at 236.855 253.365 0)
      (effects (font (size 1.524 1.524)) (justify left) hide)
    )
    (property "MPN" "CR0402-FX-2702GLF" (id 5) (at 234.315 253.365 0)
      (effects (font (size 1.524 1.524)) (justify left) hide)
    )
    (property "Val" "27k" (id 6) (at 228.6 252.7299 90)
      (effects (font (size 1.27 1.27)) (justify left))
    )
    (property "License" "Apache-2.0" (id 7) (at 201.295 268.605 0)
      (effects (font (size 1.27 1.27) (thickness 0.15)) (justify left bottom) hide)
    )
    (property "Author" "Antmicro" (id 8) (at 198.755 268.605 0)
      (effects (font (size 1.27 1.27) (thickness 0.15)) (justify left bottom) hide)
    )
    (property "Tolerance" "1%" (id 9) (at 216.535 268.605 0)
      (effects (font (size 1.27 1.27)) (justify left bottom) hide)
    )
    (pin "1")
    (pin "2")
  )

  (symbol (lib_id "sa800u-baseboard-hw:R_0R_0402") (at 223.266 266.7 180) (unit 1)
    (in_bom yes) (on_board yes)
    (property "Reference" "R31" (id 0) (at 220.726 269.113 0)
      (effects (font (size 1.524 1.524)))
    )
    (property "Value" "R_0R_0402" (id 1) (at 223.266 262.89 0)
      (effects (font (size 1.524 1.524)) hide)
    )
    (property "Footprint" "sa800u-baseboard-hw-footprints:R_0402_1005Metric" (id 2) (at 218.186 271.78 0)
      (effects (font (size 1.524 1.524)) (justify left) hide)
    )
    (property "Datasheet" "https://industrial.panasonic.com/cdbs/www-data/pdf/RDA0000/AOA0000C301.pdf" (id 3) (at 223.266 266.7 0)
      (effects (font (size 1.27 1.27)) hide)
    )
    (property "Manufacturer" "Panasonic" (id 4) (at 218.186 276.86 0)
      (effects (font (size 1.524 1.524)) (justify left) hide)
    )
    (property "MPN" "ERJ2GE0R00X" (id 5) (at 218.186 274.32 0)
      (effects (font (size 1.524 1.524)) (justify left) hide)
    )
    (property "Val" "0R" (id 6) (at 220.472 271.145 0))
    (property "DNP" "DNP" (id 7) (at 220.853 266.827 0))
    (property "License" "Apache-2.0" (id 8) (at 202.946 241.3 0)
      (effects (font (size 1.27 1.27) (thickness 0.15)) (justify left bottom) hide)
    )
    (property "Author" "Antmicro" (id 9) (at 202.946 238.76 0)
      (effects (font (size 1.27 1.27) (thickness 0.15)) (justify left bottom) hide)
    )
    (property "Tolerance" "~" (id 10) (at 202.946 256.54 0)
      (effects (font (size 1.27 1.27)) (justify left bottom) hide)
    )
    (property "Current" "1A" (id 11) (at 202.946 236.22 0)
      (effects (font (size 1.27 1.27) (thickness 0.15)) (justify left bottom) hide)
    )
    (pin "1")
    (pin "2")
  )

  (symbol (lib_id "sa800u-baseboard-hw:R_4k7_0402") (at 168.275 237.998 270) (unit 1)
    (in_bom yes) (on_board yes) (fields_autoplaced)
    (property "Reference" "R23" (id 0) (at 166.37 239.268 90)
      (effects (font (size 1.524 1.524)) (justify right))
    )
    (property "Value" "R_4k7_0402" (id 1) (at 164.465 237.998 0)
      (effects (font (size 1.524 1.524)) hide)
    )
    (property "Footprint" "sa800u-baseboard-hw-footprints:R_0402_1005Metric" (id 2) (at 173.355 243.078 0)
      (effects (font (size 1.524 1.524)) (justify left) hide)
    )
    (property "Datasheet" "https://www.bourns.com/docs/product-datasheets/cr.pdf" (id 3) (at 168.275 237.998 0)
      (effects (font (size 1.27 1.27)) hide)
    )
    (property "Manufacturer" "Bourns" (id 4) (at 178.435 243.078 0)
      (effects (font (size 1.524 1.524)) (justify left) hide)
    )
    (property "MPN" "CR0402-FX-4701GLF" (id 5) (at 175.895 243.078 0)
      (effects (font (size 1.524 1.524)) (justify left) hide)
    )
    (property "Val" "4k7" (id 6) (at 166.37 242.4429 90)
      (effects (font (size 1.27 1.27)) (justify right))
    )
    (property "License" "Apache-2.0" (id 7) (at 142.875 258.318 0)
      (effects (font (size 1.27 1.27) (thickness 0.15)) (justify left bottom) hide)
    )
    (property "Author" "Antmicro" (id 8) (at 140.335 258.318 0)
      (effects (font (size 1.27 1.27) (thickness 0.15)) (justify left bottom) hide)
    )
    (property "Tolerance" "1%" (id 9) (at 158.115 258.318 0)
      (effects (font (size 1.27 1.27)) (justify left bottom) hide)
    )
    (pin "1")
    (pin "2")
  )

  (symbol (lib_id "sa800u-baseboard-hw:R_4k7_0402") (at 181.356 237.998 270) (unit 1)
    (in_bom yes) (on_board yes) (fields_autoplaced)
    (property "Reference" "R25" (id 0) (at 183.261 239.268 90)
      (effects (font (size 1.524 1.524)) (justify left))
    )
    (property "Value" "R_4k7_0402" (id 1) (at 177.546 237.998 0)
      (effects (font (size 1.524 1.524)) hide)
    )
    (property "Footprint" "sa800u-baseboard-hw-footprints:R_0402_1005Metric" (id 2) (at 186.436 243.078 0)
      (effects (font (size 1.524 1.524)) (justify left) hide)
    )
    (property "Datasheet" "https://www.bourns.com/docs/product-datasheets/cr.pdf" (id 3) (at 181.356 237.998 0)
      (effects (font (size 1.27 1.27)) hide)
    )
    (property "Manufacturer" "Bourns" (id 4) (at 191.516 243.078 0)
      (effects (font (size 1.524 1.524)) (justify left) hide)
    )
    (property "MPN" "CR0402-FX-4701GLF" (id 5) (at 188.976 243.078 0)
      (effects (font (size 1.524 1.524)) (justify left) hide)
    )
    (property "Val" "4k7" (id 6) (at 183.261 242.4429 90)
      (effects (font (size 1.27 1.27)) (justify left))
    )
    (property "License" "Apache-2.0" (id 7) (at 155.956 258.318 0)
      (effects (font (size 1.27 1.27) (thickness 0.15)) (justify left bottom) hide)
    )
    (property "Author" "Antmicro" (id 8) (at 153.416 258.318 0)
      (effects (font (size 1.27 1.27) (thickness 0.15)) (justify left bottom) hide)
    )
    (property "Tolerance" "1%" (id 9) (at 171.196 258.318 0)
      (effects (font (size 1.27 1.27)) (justify left bottom) hide)
    )
    (pin "1")
    (pin "2")
  )

  (symbol (lib_id "sa800u-baseboard-hw:HDMI_Micro-D_46756-1001") (at 375.92 23.495 0) (unit 1)
    (in_bom yes) (on_board yes) (fields_autoplaced)
    (property "Reference" "J2" (id 0) (at 388.62 15.24 0))
    (property "Value" "HDMI_Micro-D_46756-1001" (id 1) (at 388.62 17.78 0)
      (effects (font (size 1.27 1.27)) hide)
    )
    (property "Footprint" "sa800u-baseboard-hw-footprints:HDMI_Micro-D_Molex_46765-1x01" (id 2) (at 375.92 51.435 0)
      (effects (font (size 1.27 1.27)) hide)
    )
    (property "Datasheet" "https://www.molex.com/webdocs/datasheets/pdf/en-us/0467651001_IO_CONNECTORS.pdf" (id 3) (at 375.92 23.495 0)
      (effects (font (size 1.27 1.27)) hide)
    )
    (property "MPN" "467651001" (id 4) (at 388.62 17.78 0))
    (property "Manufacturer" "Molex" (id 5) (at 375.92 56.515 0)
      (effects (font (size 1.27 1.27)) hide)
    )
    (property "Author" "Antmicro" (id 6) (at 414.02 41.275 0)
      (effects (font (size 1.27 1.27) (thickness 0.15)) (justify left bottom) hide)
    )
    (property "License" "Apache-2.0" (id 7) (at 414.02 43.815 0)
      (effects (font (size 1.27 1.27) (thickness 0.15)) (justify left bottom) hide)
    )
    (pin "1")
    (pin "10")
    (pin "11")
    (pin "12")
    (pin "13")
    (pin "14")
    (pin "15")
    (pin "16")
    (pin "17")
    (pin "18")
    (pin "19")
    (pin "2")
    (pin "3")
    (pin "4")
    (pin "5")
    (pin "6")
    (pin "7")
    (pin "8")
    (pin "9")
    (pin "SH")
  )

  (symbol (lib_id "sa800u-baseboard-hw:R_50R_0402") (at 288.925 153.67 90) (mirror x) (unit 1)
    (in_bom yes) (on_board yes) (fields_autoplaced)
    (property "Reference" "R47" (id 0) (at 290.83 154.94 90)
      (effects (font (size 1.524 1.524)) (justify right))
    )
    (property "Value" "R_50R_0402" (id 1) (at 292.735 153.67 0)
      (effects (font (size 1.524 1.524)) hide)
    )
    (property "Footprint" "sa800u-baseboard-hw-footprints:R_0402_1005Metric" (id 2) (at 283.845 158.75 0)
      (effects (font (size 1.524 1.524)) (justify left) hide)
    )
    (property "Datasheet" "https://www.bourns.com/docs/product-datasheets/cr.pdf" (id 3) (at 288.925 153.67 0)
      (effects (font (size 1.27 1.27)) hide)
    )
    (property "Manufacturer" "Bourns" (id 4) (at 278.765 158.75 0)
      (effects (font (size 1.524 1.524)) (justify left) hide)
    )
    (property "MPN" "CR0402-FX-50R0GLF" (id 5) (at 281.305 158.75 0)
      (effects (font (size 1.524 1.524)) (justify left) hide)
    )
    (property "Val" "50R" (id 6) (at 290.83 158.1149 90)
      (effects (font (size 1.27 1.27)) (justify right))
    )
    (property "License" "Apache-2.0" (id 7) (at 314.325 173.99 0)
      (effects (font (size 1.27 1.27) (thickness 0.15)) (justify left bottom) hide)
    )
    (property "Author" "Antmicro" (id 8) (at 316.865 173.99 0)
      (effects (font (size 1.27 1.27) (thickness 0.15)) (justify left bottom) hide)
    )
    (property "Tolerance" "1%" (id 9) (at 299.085 173.99 0)
      (effects (font (size 1.27 1.27)) (justify left bottom) hide)
    )
    (pin "1")
    (pin "2")
  )

  (symbol (lib_id "sa800u-baseboard-hw:R_50R_0402") (at 281.305 153.67 90) (mirror x) (unit 1)
    (in_bom yes) (on_board yes) (fields_autoplaced)
    (property "Reference" "R45" (id 0) (at 283.21 154.94 90)
      (effects (font (size 1.524 1.524)) (justify right))
    )
    (property "Value" "R_50R_0402" (id 1) (at 285.115 153.67 0)
      (effects (font (size 1.524 1.524)) hide)
    )
    (property "Footprint" "sa800u-baseboard-hw-footprints:R_0402_1005Metric" (id 2) (at 276.225 158.75 0)
      (effects (font (size 1.524 1.524)) (justify left) hide)
    )
    (property "Datasheet" "https://www.bourns.com/docs/product-datasheets/cr.pdf" (id 3) (at 281.305 153.67 0)
      (effects (font (size 1.27 1.27)) hide)
    )
    (property "Manufacturer" "Bourns" (id 4) (at 271.145 158.75 0)
      (effects (font (size 1.524 1.524)) (justify left) hide)
    )
    (property "MPN" "CR0402-FX-50R0GLF" (id 5) (at 273.685 158.75 0)
      (effects (font (size 1.524 1.524)) (justify left) hide)
    )
    (property "Val" "50R" (id 6) (at 283.21 158.1149 90)
      (effects (font (size 1.27 1.27)) (justify right))
    )
    (property "License" "Apache-2.0" (id 7) (at 306.705 173.99 0)
      (effects (font (size 1.27 1.27) (thickness 0.15)) (justify left bottom) hide)
    )
    (property "Author" "Antmicro" (id 8) (at 309.245 173.99 0)
      (effects (font (size 1.27 1.27) (thickness 0.15)) (justify left bottom) hide)
    )
    (property "Tolerance" "1%" (id 9) (at 291.465 173.99 0)
      (effects (font (size 1.27 1.27)) (justify left bottom) hide)
    )
    (pin "1")
    (pin "2")
  )

  (symbol (lib_id "sa800u-baseboard-hw:R_50R_0402") (at 273.685 153.67 90) (mirror x) (unit 1)
    (in_bom yes) (on_board yes) (fields_autoplaced)
    (property "Reference" "R42" (id 0) (at 275.59 154.94 90)
      (effects (font (size 1.524 1.524)) (justify right))
    )
    (property "Value" "R_50R_0402" (id 1) (at 277.495 153.67 0)
      (effects (font (size 1.524 1.524)) hide)
    )
    (property "Footprint" "sa800u-baseboard-hw-footprints:R_0402_1005Metric" (id 2) (at 268.605 158.75 0)
      (effects (font (size 1.524 1.524)) (justify left) hide)
    )
    (property "Datasheet" "https://www.bourns.com/docs/product-datasheets/cr.pdf" (id 3) (at 273.685 153.67 0)
      (effects (font (size 1.27 1.27)) hide)
    )
    (property "Manufacturer" "Bourns" (id 4) (at 263.525 158.75 0)
      (effects (font (size 1.524 1.524)) (justify left) hide)
    )
    (property "MPN" "CR0402-FX-50R0GLF" (id 5) (at 266.065 158.75 0)
      (effects (font (size 1.524 1.524)) (justify left) hide)
    )
    (property "Val" "50R" (id 6) (at 275.59 158.1149 90)
      (effects (font (size 1.27 1.27)) (justify right))
    )
    (property "License" "Apache-2.0" (id 7) (at 299.085 173.99 0)
      (effects (font (size 1.27 1.27) (thickness 0.15)) (justify left bottom) hide)
    )
    (property "Author" "Antmicro" (id 8) (at 301.625 173.99 0)
      (effects (font (size 1.27 1.27) (thickness 0.15)) (justify left bottom) hide)
    )
    (property "Tolerance" "1%" (id 9) (at 283.845 173.99 0)
      (effects (font (size 1.27 1.27)) (justify left bottom) hide)
    )
    (pin "1")
    (pin "2")
  )

  (symbol (lib_id "sa800u-baseboard-hw:R_50R_0402") (at 266.065 153.67 90) (mirror x) (unit 1)
    (in_bom yes) (on_board yes) (fields_autoplaced)
    (property "Reference" "R40" (id 0) (at 267.97 154.94 90)
      (effects (font (size 1.524 1.524)) (justify right))
    )
    (property "Value" "R_50R_0402" (id 1) (at 269.875 153.67 0)
      (effects (font (size 1.524 1.524)) hide)
    )
    (property "Footprint" "sa800u-baseboard-hw-footprints:R_0402_1005Metric" (id 2) (at 260.985 158.75 0)
      (effects (font (size 1.524 1.524)) (justify left) hide)
    )
    (property "Datasheet" "https://www.bourns.com/docs/product-datasheets/cr.pdf" (id 3) (at 266.065 153.67 0)
      (effects (font (size 1.27 1.27)) hide)
    )
    (property "Manufacturer" "Bourns" (id 4) (at 255.905 158.75 0)
      (effects (font (size 1.524 1.524)) (justify left) hide)
    )
    (property "MPN" "CR0402-FX-50R0GLF" (id 5) (at 258.445 158.75 0)
      (effects (font (size 1.524 1.524)) (justify left) hide)
    )
    (property "Val" "50R" (id 6) (at 267.97 158.1149 90)
      (effects (font (size 1.27 1.27)) (justify right))
    )
    (property "License" "Apache-2.0" (id 7) (at 291.465 173.99 0)
      (effects (font (size 1.27 1.27) (thickness 0.15)) (justify left bottom) hide)
    )
    (property "Author" "Antmicro" (id 8) (at 294.005 173.99 0)
      (effects (font (size 1.27 1.27) (thickness 0.15)) (justify left bottom) hide)
    )
    (property "Tolerance" "1%" (id 9) (at 276.225 173.99 0)
      (effects (font (size 1.27 1.27)) (justify left bottom) hide)
    )
    (pin "1")
    (pin "2")
  )

  (symbol (lib_id "sa800u-baseboard-hw:R_50R_0402") (at 258.445 153.67 90) (mirror x) (unit 1)
    (in_bom yes) (on_board yes) (fields_autoplaced)
    (property "Reference" "R39" (id 0) (at 260.35 154.94 90)
      (effects (font (size 1.524 1.524)) (justify right))
    )
    (property "Value" "R_50R_0402" (id 1) (at 262.255 153.67 0)
      (effects (font (size 1.524 1.524)) hide)
    )
    (property "Footprint" "sa800u-baseboard-hw-footprints:R_0402_1005Metric" (id 2) (at 253.365 158.75 0)
      (effects (font (size 1.524 1.524)) (justify left) hide)
    )
    (property "Datasheet" "https://www.bourns.com/docs/product-datasheets/cr.pdf" (id 3) (at 258.445 153.67 0)
      (effects (font (size 1.27 1.27)) hide)
    )
    (property "Manufacturer" "Bourns" (id 4) (at 248.285 158.75 0)
      (effects (font (size 1.524 1.524)) (justify left) hide)
    )
    (property "MPN" "CR0402-FX-50R0GLF" (id 5) (at 250.825 158.75 0)
      (effects (font (size 1.524 1.524)) (justify left) hide)
    )
    (property "Val" "50R" (id 6) (at 260.35 158.1149 90)
      (effects (font (size 1.27 1.27)) (justify right))
    )
    (property "License" "Apache-2.0" (id 7) (at 283.845 173.99 0)
      (effects (font (size 1.27 1.27) (thickness 0.15)) (justify left bottom) hide)
    )
    (property "Author" "Antmicro" (id 8) (at 286.385 173.99 0)
      (effects (font (size 1.27 1.27) (thickness 0.15)) (justify left bottom) hide)
    )
    (property "Tolerance" "1%" (id 9) (at 268.605 173.99 0)
      (effects (font (size 1.27 1.27)) (justify left bottom) hide)
    )
    (pin "1")
    (pin "2")
  )

  (symbol (lib_id "sa800u-baseboard-hw:R_50R_0402") (at 250.825 153.67 90) (mirror x) (unit 1)
    (in_bom yes) (on_board yes) (fields_autoplaced)
    (property "Reference" "R38" (id 0) (at 252.73 154.94 90)
      (effects (font (size 1.524 1.524)) (justify right))
    )
    (property "Value" "R_50R_0402" (id 1) (at 254.635 153.67 0)
      (effects (font (size 1.524 1.524)) hide)
    )
    (property "Footprint" "sa800u-baseboard-hw-footprints:R_0402_1005Metric" (id 2) (at 245.745 158.75 0)
      (effects (font (size 1.524 1.524)) (justify left) hide)
    )
    (property "Datasheet" "https://www.bourns.com/docs/product-datasheets/cr.pdf" (id 3) (at 250.825 153.67 0)
      (effects (font (size 1.27 1.27)) hide)
    )
    (property "Manufacturer" "Bourns" (id 4) (at 240.665 158.75 0)
      (effects (font (size 1.524 1.524)) (justify left) hide)
    )
    (property "MPN" "CR0402-FX-50R0GLF" (id 5) (at 243.205 158.75 0)
      (effects (font (size 1.524 1.524)) (justify left) hide)
    )
    (property "Val" "50R" (id 6) (at 252.73 158.1149 90)
      (effects (font (size 1.27 1.27)) (justify right))
    )
    (property "License" "Apache-2.0" (id 7) (at 276.225 173.99 0)
      (effects (font (size 1.27 1.27) (thickness 0.15)) (justify left bottom) hide)
    )
    (property "Author" "Antmicro" (id 8) (at 278.765 173.99 0)
      (effects (font (size 1.27 1.27) (thickness 0.15)) (justify left bottom) hide)
    )
    (property "Tolerance" "1%" (id 9) (at 260.985 173.99 0)
      (effects (font (size 1.27 1.27)) (justify left bottom) hide)
    )
    (pin "1")
    (pin "2")
  )

  (symbol (lib_id "sa800u-baseboard-hw:R_50R_0402") (at 243.205 153.67 90) (mirror x) (unit 1)
    (in_bom yes) (on_board yes) (fields_autoplaced)
    (property "Reference" "R37" (id 0) (at 245.11 154.94 90)
      (effects (font (size 1.524 1.524)) (justify right))
    )
    (property "Value" "R_50R_0402" (id 1) (at 247.015 153.67 0)
      (effects (font (size 1.524 1.524)) hide)
    )
    (property "Footprint" "sa800u-baseboard-hw-footprints:R_0402_1005Metric" (id 2) (at 238.125 158.75 0)
      (effects (font (size 1.524 1.524)) (justify left) hide)
    )
    (property "Datasheet" "https://www.bourns.com/docs/product-datasheets/cr.pdf" (id 3) (at 243.205 153.67 0)
      (effects (font (size 1.27 1.27)) hide)
    )
    (property "Manufacturer" "Bourns" (id 4) (at 233.045 158.75 0)
      (effects (font (size 1.524 1.524)) (justify left) hide)
    )
    (property "MPN" "CR0402-FX-50R0GLF" (id 5) (at 235.585 158.75 0)
      (effects (font (size 1.524 1.524)) (justify left) hide)
    )
    (property "Val" "50R" (id 6) (at 245.11 158.1149 90)
      (effects (font (size 1.27 1.27)) (justify right))
    )
    (property "License" "Apache-2.0" (id 7) (at 268.605 173.99 0)
      (effects (font (size 1.27 1.27) (thickness 0.15)) (justify left bottom) hide)
    )
    (property "Author" "Antmicro" (id 8) (at 271.145 173.99 0)
      (effects (font (size 1.27 1.27) (thickness 0.15)) (justify left bottom) hide)
    )
    (property "Tolerance" "1%" (id 9) (at 253.365 173.99 0)
      (effects (font (size 1.27 1.27)) (justify left bottom) hide)
    )
    (pin "1")
    (pin "2")
  )

  (symbol (lib_id "sa800u-baseboard-hw:R_50R_0402") (at 235.585 153.67 90) (mirror x) (unit 1)
    (in_bom yes) (on_board yes) (fields_autoplaced)
    (property "Reference" "R35" (id 0) (at 237.49 154.94 90)
      (effects (font (size 1.524 1.524)) (justify right))
    )
    (property "Value" "R_50R_0402" (id 1) (at 239.395 153.67 0)
      (effects (font (size 1.524 1.524)) hide)
    )
    (property "Footprint" "sa800u-baseboard-hw-footprints:R_0402_1005Metric" (id 2) (at 230.505 158.75 0)
      (effects (font (size 1.524 1.524)) (justify left) hide)
    )
    (property "Datasheet" "https://www.bourns.com/docs/product-datasheets/cr.pdf" (id 3) (at 235.585 153.67 0)
      (effects (font (size 1.27 1.27)) hide)
    )
    (property "Manufacturer" "Bourns" (id 4) (at 225.425 158.75 0)
      (effects (font (size 1.524 1.524)) (justify left) hide)
    )
    (property "MPN" "CR0402-FX-50R0GLF" (id 5) (at 227.965 158.75 0)
      (effects (font (size 1.524 1.524)) (justify left) hide)
    )
    (property "Val" "50R" (id 6) (at 237.49 158.1149 90)
      (effects (font (size 1.27 1.27)) (justify right))
    )
    (property "License" "Apache-2.0" (id 7) (at 260.985 173.99 0)
      (effects (font (size 1.27 1.27) (thickness 0.15)) (justify left bottom) hide)
    )
    (property "Author" "Antmicro" (id 8) (at 263.525 173.99 0)
      (effects (font (size 1.27 1.27) (thickness 0.15)) (justify left bottom) hide)
    )
    (property "Tolerance" "1%" (id 9) (at 245.745 173.99 0)
      (effects (font (size 1.27 1.27)) (justify left bottom) hide)
    )
    (pin "1")
    (pin "2")
  )

  (symbol (lib_id "sa800u-baseboard-hw:C_100n_0402") (at 298.196 162.56 0) (unit 1)
    (in_bom yes) (on_board yes)
    (property "Reference" "C50" (id 0) (at 303.911 161.417 0)
      (effects (font (size 1.524 1.524)))
    )
    (property "Value" "C_100n_0402" (id 1) (at 298.196 166.37 0)
      (effects (font (size 1.524 1.524)) hide)
    )
    (property "Footprint" "sa800u-baseboard-hw-footprints:C_0402_1005Metric" (id 2) (at 303.276 157.48 0)
      (effects (font (size 1.524 1.524)) (justify left) hide)
    )
    (property "Datasheet" "https://search.murata.co.jp/Ceramy/image/img/A01X/G101/ENG/GRM155R61H104KE14-01.pdf" (id 3) (at 298.196 162.56 0)
      (effects (font (size 1.27 1.27)) hide)
    )
    (property "Manufacturer" "Murata" (id 4) (at 303.276 152.4 0)
      (effects (font (size 1.524 1.524)) (justify left) hide)
    )
    (property "MPN" "GRM155R61H104KE14D" (id 5) (at 303.276 154.94 0)
      (effects (font (size 1.524 1.524)) (justify left) hide)
    )
    (property "Val" "100n" (id 6) (at 304.038 163.957 0))
    (property "License" "Apache-2.0" (id 7) (at 318.516 185.42 0)
      (effects (font (size 1.27 1.27) (thickness 0.15)) (justify left bottom) hide)
    )
    (property "Author" "Antmicro" (id 8) (at 318.516 187.96 0)
      (effects (font (size 1.27 1.27) (thickness 0.15)) (justify left bottom) hide)
    )
    (property "Voltage" "50V" (id 9) (at 318.516 190.5 0)
      (effects (font (size 1.27 1.27)) (justify left bottom) hide)
    )
    (property "Dielectric" "X5R" (id 10) (at 318.516 193.04 0)
      (effects (font (size 1.27 1.27)) (justify left bottom) hide)
    )
    (pin "1")
    (pin "2")
  )

  (symbol (lib_id "sa800u-baseboard-hw:C_100n_0402") (at 295.021 165.1 0) (unit 1)
    (in_bom yes) (on_board yes)
    (property "Reference" "C46" (id 0) (at 294.513 163.83 0)
      (effects (font (size 1.524 1.524)))
    )
    (property "Value" "C_100n_0402" (id 1) (at 295.021 168.91 0)
      (effects (font (size 1.524 1.524)) hide)
    )
    (property "Footprint" "sa800u-baseboard-hw-footprints:C_0402_1005Metric" (id 2) (at 300.101 160.02 0)
      (effects (font (size 1.524 1.524)) (justify left) hide)
    )
    (property "Datasheet" "https://search.murata.co.jp/Ceramy/image/img/A01X/G101/ENG/GRM155R61H104KE14-01.pdf" (id 3) (at 295.021 165.1 0)
      (effects (font (size 1.27 1.27)) hide)
    )
    (property "Manufacturer" "Murata" (id 4) (at 300.101 154.94 0)
      (effects (font (size 1.524 1.524)) (justify left) hide)
    )
    (property "MPN" "GRM155R61H104KE14D" (id 5) (at 300.101 157.48 0)
      (effects (font (size 1.524 1.524)) (justify left) hide)
    )
    (property "Val" "100n" (id 6) (at 294.64 166.37 0))
    (property "License" "Apache-2.0" (id 7) (at 315.341 187.96 0)
      (effects (font (size 1.27 1.27) (thickness 0.15)) (justify left bottom) hide)
    )
    (property "Author" "Antmicro" (id 8) (at 315.341 190.5 0)
      (effects (font (size 1.27 1.27) (thickness 0.15)) (justify left bottom) hide)
    )
    (property "Voltage" "50V" (id 9) (at 315.341 193.04 0)
      (effects (font (size 1.27 1.27)) (justify left bottom) hide)
    )
    (property "Dielectric" "X5R" (id 10) (at 315.341 195.58 0)
      (effects (font (size 1.27 1.27)) (justify left bottom) hide)
    )
    (pin "1")
    (pin "2")
  )

  (symbol (lib_id "sa800u-baseboard-hw:C_100n_0402") (at 298.196 170.18 0) (unit 1)
    (in_bom yes) (on_board yes)
    (property "Reference" "C51" (id 0) (at 303.911 168.91 0)
      (effects (font (size 1.524 1.524)))
    )
    (property "Value" "C_100n_0402" (id 1) (at 298.196 173.99 0)
      (effects (font (size 1.524 1.524)) hide)
    )
    (property "Footprint" "sa800u-baseboard-hw-footprints:C_0402_1005Metric" (id 2) (at 303.276 165.1 0)
      (effects (font (size 1.524 1.524)) (justify left) hide)
    )
    (property "Datasheet" "https://search.murata.co.jp/Ceramy/image/img/A01X/G101/ENG/GRM155R61H104KE14-01.pdf" (id 3) (at 298.196 170.18 0)
      (effects (font (size 1.27 1.27)) hide)
    )
    (property "Manufacturer" "Murata" (id 4) (at 303.276 160.02 0)
      (effects (font (size 1.524 1.524)) (justify left) hide)
    )
    (property "MPN" "GRM155R61H104KE14D" (id 5) (at 303.276 162.56 0)
      (effects (font (size 1.524 1.524)) (justify left) hide)
    )
    (property "Val" "100n" (id 6) (at 304.038 171.45 0))
    (property "License" "Apache-2.0" (id 7) (at 318.516 193.04 0)
      (effects (font (size 1.27 1.27) (thickness 0.15)) (justify left bottom) hide)
    )
    (property "Author" "Antmicro" (id 8) (at 318.516 195.58 0)
      (effects (font (size 1.27 1.27) (thickness 0.15)) (justify left bottom) hide)
    )
    (property "Voltage" "50V" (id 9) (at 318.516 198.12 0)
      (effects (font (size 1.27 1.27)) (justify left bottom) hide)
    )
    (property "Dielectric" "X5R" (id 10) (at 318.516 200.66 0)
      (effects (font (size 1.27 1.27)) (justify left bottom) hide)
    )
    (pin "1")
    (pin "2")
  )

  (symbol (lib_id "sa800u-baseboard-hw:C_100n_0402") (at 295.021 172.72 0) (unit 1)
    (in_bom yes) (on_board yes)
    (property "Reference" "C47" (id 0) (at 294.513 171.577 0)
      (effects (font (size 1.524 1.524)))
    )
    (property "Value" "C_100n_0402" (id 1) (at 295.021 176.53 0)
      (effects (font (size 1.524 1.524)) hide)
    )
    (property "Footprint" "sa800u-baseboard-hw-footprints:C_0402_1005Metric" (id 2) (at 300.101 167.64 0)
      (effects (font (size 1.524 1.524)) (justify left) hide)
    )
    (property "Datasheet" "https://search.murata.co.jp/Ceramy/image/img/A01X/G101/ENG/GRM155R61H104KE14-01.pdf" (id 3) (at 295.021 172.72 0)
      (effects (font (size 1.27 1.27)) hide)
    )
    (property "Manufacturer" "Murata" (id 4) (at 300.101 162.56 0)
      (effects (font (size 1.524 1.524)) (justify left) hide)
    )
    (property "MPN" "GRM155R61H104KE14D" (id 5) (at 300.101 165.1 0)
      (effects (font (size 1.524 1.524)) (justify left) hide)
    )
    (property "Val" "100n" (id 6) (at 294.513 174.117 0))
    (property "License" "Apache-2.0" (id 7) (at 315.341 195.58 0)
      (effects (font (size 1.27 1.27) (thickness 0.15)) (justify left bottom) hide)
    )
    (property "Author" "Antmicro" (id 8) (at 315.341 198.12 0)
      (effects (font (size 1.27 1.27) (thickness 0.15)) (justify left bottom) hide)
    )
    (property "Voltage" "50V" (id 9) (at 315.341 200.66 0)
      (effects (font (size 1.27 1.27)) (justify left bottom) hide)
    )
    (property "Dielectric" "X5R" (id 10) (at 315.341 203.2 0)
      (effects (font (size 1.27 1.27)) (justify left bottom) hide)
    )
    (pin "1")
    (pin "2")
  )

  (symbol (lib_id "sa800u-baseboard-hw:C_100n_0402") (at 298.196 177.8 0) (unit 1)
    (in_bom yes) (on_board yes)
    (property "Reference" "C52" (id 0) (at 303.784 176.276 0)
      (effects (font (size 1.524 1.524)))
    )
    (property "Value" "C_100n_0402" (id 1) (at 298.196 181.61 0)
      (effects (font (size 1.524 1.524)) hide)
    )
    (property "Footprint" "sa800u-baseboard-hw-footprints:C_0402_1005Metric" (id 2) (at 303.276 172.72 0)
      (effects (font (size 1.524 1.524)) (justify left) hide)
    )
    (property "Datasheet" "https://search.murata.co.jp/Ceramy/image/img/A01X/G101/ENG/GRM155R61H104KE14-01.pdf" (id 3) (at 298.196 177.8 0)
      (effects (font (size 1.27 1.27)) hide)
    )
    (property "Manufacturer" "Murata" (id 4) (at 303.276 167.64 0)
      (effects (font (size 1.524 1.524)) (justify left) hide)
    )
    (property "MPN" "GRM155R61H104KE14D" (id 5) (at 303.276 170.18 0)
      (effects (font (size 1.524 1.524)) (justify left) hide)
    )
    (property "Val" "100n" (id 6) (at 303.911 178.943 0))
    (property "License" "Apache-2.0" (id 7) (at 318.516 200.66 0)
      (effects (font (size 1.27 1.27) (thickness 0.15)) (justify left bottom) hide)
    )
    (property "Author" "Antmicro" (id 8) (at 318.516 203.2 0)
      (effects (font (size 1.27 1.27) (thickness 0.15)) (justify left bottom) hide)
    )
    (property "Voltage" "50V" (id 9) (at 318.516 205.74 0)
      (effects (font (size 1.27 1.27)) (justify left bottom) hide)
    )
    (property "Dielectric" "X5R" (id 10) (at 318.516 208.28 0)
      (effects (font (size 1.27 1.27)) (justify left bottom) hide)
    )
    (pin "1")
    (pin "2")
  )

  (symbol (lib_id "sa800u-baseboard-hw:PUSB3F96X_PASS") (at 337.82 80.01 270) (unit 1)
    (in_bom yes) (on_board yes)
    (property "Reference" "D4" (id 0) (at 325.374 94.234 90)
      (effects (font (size 1.524 1.524)) (justify left))
    )
    (property "Value" "PUSB3F96X_PASS" (id 1) (at 325.374 98.044 90)
      (effects (font (size 1.524 1.524)) (justify left))
    )
    (property "Footprint" "sa800u-baseboard-hw-footprints:Nexperia_DFN-10_2.5x1mm_P0.5mm" (id 2) (at 323.85 85.09 0)
      (effects (font (size 1.524 1.524)) hide)
    )
    (property "Datasheet" "https://pl.mouser.com/datasheet/2/916/PUSB3F96-1600324.pdf" (id 3) (at 337.82 80.01 0)
      (effects (font (size 1.524 1.524)) hide)
    )
    (property "Manufacturer" "Nexperia" (id 4) (at 321.31 85.09 0)
      (effects (font (size 1.27 1.27)) hide)
    )
    (property "MPN" "PUSB3F96X" (id 5) (at 321.31 85.09 0)
      (effects (font (size 1.27 1.27)) hide)
    )
    (property "Author" "Antmicro" (id 6) (at 320.04 105.41 0)
      (effects (font (size 1.27 1.27) (thickness 0.15)) (justify left bottom) hide)
    )
    (property "License" "Apache-2.0" (id 7) (at 317.5 105.41 0)
      (effects (font (size 1.27 1.27) (thickness 0.15)) (justify left bottom) hide)
    )
    (pin "1")
    (pin "10")
    (pin "2")
    (pin "3")
    (pin "4")
    (pin "5")
    (pin "6")
    (pin "7")
    (pin "8")
    (pin "9")
  )

  (symbol (lib_id "sa800u-baseboard-hw:L_350n_1.4A_0603") (at 29.337 31.115 0) (unit 1)
    (in_bom yes) (on_board yes) (fields_autoplaced)
    (property "Reference" "L1" (id 0) (at 31.877 25.4 0))
    (property "Value" "L_350n_1.4A_0603" (id 1) (at 43.307 33.655 0)
      (effects (font (size 1.27 1.27) (thickness 0.15)) (justify left bottom) hide)
    )
    (property "Footprint" "sa800u-baseboard-hw-footprints:L_0603_1608Metric" (id 2) (at 43.307 38.735 0)
      (effects (font (size 1.27 1.27) (thickness 0.15)) (justify left bottom) hide)
    )
    (property "Datasheet" "https://pl.mouser.com/datasheet/2/396/wound07_e-1628381.pdf" (id 3) (at 43.307 41.275 0)
      (effects (font (size 1.27 1.27) (thickness 0.15)) (justify left bottom) hide)
    )
    (property "MPN" "BRC1608TR35M" (id 4) (at 43.307 46.355 0)
      (effects (font (size 1.27 1.27) (thickness 0.15)) (justify left bottom) hide)
    )
    (property "Manufacturer" "Taiyo Yuden" (id 5) (at 43.307 43.815 0)
      (effects (font (size 1.27 1.27) (thickness 0.15)) (justify left bottom) hide)
    )
    (property "Val" "350n/1.4A" (id 6) (at 31.877 27.94 0)
      (effects (font (size 1.27 1.27) (thickness 0.15)))
    )
    (property "ISat" "" (id 7) (at 43.307 47.625 0)
      (effects (font (size 1.27 1.27)) (justify left) hide)
    )
    (property "IMax" "" (id 8) (at 43.307 51.435 0)
      (effects (font (size 1.27 1.27) (thickness 0.15)) (justify left bottom) hide)
    )
    (property "Size" "" (id 9) (at 43.307 53.975 0)
      (effects (font (size 1.27 1.27) (thickness 0.15)) (justify left bottom) hide)
    )
    (property "Author" "Antmicro" (id 10) (at 43.307 56.515 0)
      (effects (font (size 1.27 1.27) (thickness 0.15)) (justify left bottom) hide)
    )
    (property "License" "Apache-2.0" (id 11) (at 43.307 59.055 0)
      (effects (font (size 1.27 1.27) (thickness 0.15)) (justify left bottom) hide)
    )
    (pin "1")
    (pin "2")
  )

  (symbol (lib_id "sa800u-baseboard-hw:L_350n_1.4A_0603") (at 29.337 37.465 0) (unit 1)
    (in_bom yes) (on_board yes) (fields_autoplaced)
    (property "Reference" "L2" (id 0) (at 31.877 31.75 0))
    (property "Value" "L_350n_1.4A_0603" (id 1) (at 43.307 40.005 0)
      (effects (font (size 1.27 1.27) (thickness 0.15)) (justify left bottom) hide)
    )
    (property "Footprint" "sa800u-baseboard-hw-footprints:L_0603_1608Metric" (id 2) (at 43.307 45.085 0)
      (effects (font (size 1.27 1.27) (thickness 0.15)) (justify left bottom) hide)
    )
    (property "Datasheet" "https://pl.mouser.com/datasheet/2/396/wound07_e-1628381.pdf" (id 3) (at 43.307 47.625 0)
      (effects (font (size 1.27 1.27) (thickness 0.15)) (justify left bottom) hide)
    )
    (property "MPN" "BRC1608TR35M" (id 4) (at 43.307 52.705 0)
      (effects (font (size 1.27 1.27) (thickness 0.15)) (justify left bottom) hide)
    )
    (property "Manufacturer" "Taiyo Yuden" (id 5) (at 43.307 50.165 0)
      (effects (font (size 1.27 1.27) (thickness 0.15)) (justify left bottom) hide)
    )
    (property "Val" "350n/1.4A" (id 6) (at 31.877 34.29 0)
      (effects (font (size 1.27 1.27) (thickness 0.15)))
    )
    (property "ISat" "" (id 7) (at 43.307 53.975 0)
      (effects (font (size 1.27 1.27)) (justify left) hide)
    )
    (property "IMax" "" (id 8) (at 43.307 57.785 0)
      (effects (font (size 1.27 1.27) (thickness 0.15)) (justify left bottom) hide)
    )
    (property "Size" "" (id 9) (at 43.307 60.325 0)
      (effects (font (size 1.27 1.27) (thickness 0.15)) (justify left bottom) hide)
    )
    (property "Author" "Antmicro" (id 10) (at 43.307 62.865 0)
      (effects (font (size 1.27 1.27) (thickness 0.15)) (justify left bottom) hide)
    )
    (property "License" "Apache-2.0" (id 11) (at 43.307 65.405 0)
      (effects (font (size 1.27 1.27) (thickness 0.15)) (justify left bottom) hide)
    )
    (pin "1")
    (pin "2")
  )

  (symbol (lib_id "sa800u-baseboard-hw:L_350n_1.4A_0603") (at 29.337 45.085 0) (unit 1)
    (in_bom yes) (on_board yes) (fields_autoplaced)
    (property "Reference" "L3" (id 0) (at 31.877 39.37 0))
    (property "Value" "L_350n_1.4A_0603" (id 1) (at 43.307 47.625 0)
      (effects (font (size 1.27 1.27) (thickness 0.15)) (justify left bottom) hide)
    )
    (property "Footprint" "sa800u-baseboard-hw-footprints:L_0603_1608Metric" (id 2) (at 43.307 52.705 0)
      (effects (font (size 1.27 1.27) (thickness 0.15)) (justify left bottom) hide)
    )
    (property "Datasheet" "https://pl.mouser.com/datasheet/2/396/wound07_e-1628381.pdf" (id 3) (at 43.307 55.245 0)
      (effects (font (size 1.27 1.27) (thickness 0.15)) (justify left bottom) hide)
    )
    (property "MPN" "BRC1608TR35M" (id 4) (at 43.307 60.325 0)
      (effects (font (size 1.27 1.27) (thickness 0.15)) (justify left bottom) hide)
    )
    (property "Manufacturer" "Taiyo Yuden" (id 5) (at 43.307 57.785 0)
      (effects (font (size 1.27 1.27) (thickness 0.15)) (justify left bottom) hide)
    )
    (property "Val" "350n/1.4A" (id 6) (at 31.877 41.91 0)
      (effects (font (size 1.27 1.27) (thickness 0.15)))
    )
    (property "ISat" "" (id 7) (at 43.307 61.595 0)
      (effects (font (size 1.27 1.27)) (justify left) hide)
    )
    (property "IMax" "" (id 8) (at 43.307 65.405 0)
      (effects (font (size 1.27 1.27) (thickness 0.15)) (justify left bottom) hide)
    )
    (property "Size" "" (id 9) (at 43.307 67.945 0)
      (effects (font (size 1.27 1.27) (thickness 0.15)) (justify left bottom) hide)
    )
    (property "Author" "Antmicro" (id 10) (at 43.307 70.485 0)
      (effects (font (size 1.27 1.27) (thickness 0.15)) (justify left bottom) hide)
    )
    (property "License" "Apache-2.0" (id 11) (at 43.307 73.025 0)
      (effects (font (size 1.27 1.27) (thickness 0.15)) (justify left bottom) hide)
    )
    (pin "1")
    (pin "2")
  )

  (symbol (lib_id "sa800u-baseboard-hw:C_100n_0402") (at 154.305 52.07 270) (unit 1)
    (in_bom yes) (on_board yes) (fields_autoplaced)
    (property "Reference" "C37" (id 0) (at 157.353 53.3463 90)
      (effects (font (size 1.524 1.524)) (justify left))
    )
    (property "Value" "C_100n_0402" (id 1) (at 150.495 52.07 0)
      (effects (font (size 1.524 1.524)) hide)
    )
    (property "Footprint" "sa800u-baseboard-hw-footprints:C_0402_1005Metric" (id 2) (at 159.385 57.15 0)
      (effects (font (size 1.524 1.524)) (justify left) hide)
    )
    (property "Datasheet" "https://search.murata.co.jp/Ceramy/image/img/A01X/G101/ENG/GRM155R61H104KE14-01.pdf" (id 3) (at 154.305 52.07 0)
      (effects (font (size 1.27 1.27)) hide)
    )
    (property "Manufacturer" "Murata" (id 4) (at 164.465 57.15 0)
      (effects (font (size 1.524 1.524)) (justify left) hide)
    )
    (property "MPN" "GRM155R61H104KE14D" (id 5) (at 161.925 57.15 0)
      (effects (font (size 1.524 1.524)) (justify left) hide)
    )
    (property "Val" "100n" (id 6) (at 157.353 56.5212 90)
      (effects (font (size 1.27 1.27)) (justify left))
    )
    (property "License" "Apache-2.0" (id 7) (at 131.445 72.39 0)
      (effects (font (size 1.27 1.27) (thickness 0.15)) (justify left bottom) hide)
    )
    (property "Author" "Antmicro" (id 8) (at 128.905 72.39 0)
      (effects (font (size 1.27 1.27) (thickness 0.15)) (justify left bottom) hide)
    )
    (property "Voltage" "50V" (id 9) (at 126.365 72.39 0)
      (effects (font (size 1.27 1.27)) (justify left bottom) hide)
    )
    (property "Dielectric" "X5R" (id 10) (at 123.825 72.39 0)
      (effects (font (size 1.27 1.27)) (justify left bottom) hide)
    )
    (pin "1")
    (pin "2")
  )

  (symbol (lib_id "sa800u-baseboard-hw:PWR_FLAG") (at 47.625 55.245 0) (unit 1)
    (in_bom yes) (on_board yes) (fields_autoplaced)
    (property "Reference" "#FLG07" (id 0) (at 47.625 53.34 0)
      (effects (font (size 1.27 1.27)) hide)
    )
    (property "Value" "PWR_FLAG" (id 1) (at 47.625 49.53 0))
    (property "Footprint" "" (id 2) (at 47.625 55.245 0)
      (effects (font (size 1.27 1.27)) hide)
    )
    (property "Datasheet" "~" (id 3) (at 47.625 55.245 0)
      (effects (font (size 1.27 1.27)) hide)
    )
    (pin "1")
  )

  (symbol (lib_id "sa800u-baseboard-hw:LT9611") (at 95.885 99.695 0) (unit 1)
    (in_bom yes) (on_board yes) (fields_autoplaced)
    (property "Reference" "U3" (id 0) (at 112.395 92.71 0))
    (property "Value" "LT9611" (id 1) (at 112.395 95.25 0))
    (property "Footprint" "sa800u-baseboard-hw-footprints:QFN-64-1EP_7.5x7.5mm_P0.4mm" (id 2) (at 95.885 99.695 0)
      (effects (font (size 1.27 1.27)) hide)
    )
    (property "Datasheet" "" (id 3) (at 95.885 99.695 0)
      (effects (font (size 1.27 1.27)) hide)
    )
    (property "MPN" "LT9611" (id 4) (at 95.885 38.354 0)
      (effects (font (size 1.27 1.27)) hide)
    )
    (property "Manufacturer" "Lontium" (id 5) (at 95.885 40.6654 0)
      (effects (font (size 1.27 1.27)) hide)
    )
    (property "Author" "Antmicro" (id 6) (at 144.145 120.015 0)
      (effects (font (size 1.27 1.27) (thickness 0.15)) (justify left bottom) hide)
    )
    (property "License" "Apache-2.0" (id 7) (at 144.145 122.555 0)
      (effects (font (size 1.27 1.27) (thickness 0.15)) (justify left bottom) hide)
    )
    (pin "1")
    (pin "10")
    (pin "11")
    (pin "12")
    (pin "13")
    (pin "14")
    (pin "15")
    (pin "16")
    (pin "17")
    (pin "18")
    (pin "19")
    (pin "2")
    (pin "20")
    (pin "21")
    (pin "22")
    (pin "23")
    (pin "24")
    (pin "25")
    (pin "26")
    (pin "27")
    (pin "28")
    (pin "29")
    (pin "3")
    (pin "30")
    (pin "31")
    (pin "32")
    (pin "33")
    (pin "34")
    (pin "35")
    (pin "36")
    (pin "37")
    (pin "38")
    (pin "39")
    (pin "4")
    (pin "40")
    (pin "41")
    (pin "42")
    (pin "43")
    (pin "44")
    (pin "45")
    (pin "46")
    (pin "47")
    (pin "48")
    (pin "49")
    (pin "5")
    (pin "50")
    (pin "51")
    (pin "52")
    (pin "53")
    (pin "54")
    (pin "55")
    (pin "56")
    (pin "57")
    (pin "58")
    (pin "59")
    (pin "6")
    (pin "60")
    (pin "61")
    (pin "62")
    (pin "63")
    (pin "64")
    (pin "65")
    (pin "7")
    (pin "8")
    (pin "9")
  )

  (symbol (lib_id "sa800u-baseboard-hw:PWR_FLAG") (at 47.625 31.115 0) (unit 1)
    (in_bom yes) (on_board yes) (fields_autoplaced)
    (property "Reference" "#FLG04" (id 0) (at 47.625 29.21 0)
      (effects (font (size 1.27 1.27)) hide)
    )
    (property "Value" "PWR_FLAG" (id 1) (at 47.625 25.4 0))
    (property "Footprint" "" (id 2) (at 47.625 31.115 0)
      (effects (font (size 1.27 1.27)) hide)
    )
    (property "Datasheet" "~" (id 3) (at 47.625 31.115 0)
      (effects (font (size 1.27 1.27)) hide)
    )
    (pin "1")
  )

  (symbol (lib_id "sa800u-baseboard-hw:PWR_FLAG") (at 47.625 37.465 0) (unit 1)
    (in_bom yes) (on_board yes) (fields_autoplaced)
    (property "Reference" "#FLG05" (id 0) (at 47.625 35.56 0)
      (effects (font (size 1.27 1.27)) hide)
    )
    (property "Value" "PWR_FLAG" (id 1) (at 47.625 31.75 0))
    (property "Footprint" "" (id 2) (at 47.625 37.465 0)
      (effects (font (size 1.27 1.27)) hide)
    )
    (property "Datasheet" "~" (id 3) (at 47.625 37.465 0)
      (effects (font (size 1.27 1.27)) hide)
    )
    (pin "1")
  )

  (symbol (lib_id "sa800u-baseboard-hw:PWR_FLAG") (at 47.625 45.085 0) (unit 1)
    (in_bom yes) (on_board yes) (fields_autoplaced)
    (property "Reference" "#FLG06" (id 0) (at 47.625 43.18 0)
      (effects (font (size 1.27 1.27)) hide)
    )
    (property "Value" "PWR_FLAG" (id 1) (at 47.625 39.37 0))
    (property "Footprint" "" (id 2) (at 47.625 45.085 0)
      (effects (font (size 1.27 1.27)) hide)
    )
    (property "Datasheet" "~" (id 3) (at 47.625 45.085 0)
      (effects (font (size 1.27 1.27)) hide)
    )
    (pin "1")
  )

  (symbol (lib_id "sa800u-baseboard-hw:PWR_FLAG") (at 47.625 61.595 0) (unit 1)
    (in_bom yes) (on_board yes) (fields_autoplaced)
    (property "Reference" "#FLG08" (id 0) (at 47.625 59.69 0)
      (effects (font (size 1.27 1.27)) hide)
    )
    (property "Value" "PWR_FLAG" (id 1) (at 47.625 55.88 0))
    (property "Footprint" "" (id 2) (at 47.625 61.595 0)
      (effects (font (size 1.27 1.27)) hide)
    )
    (property "Datasheet" "~" (id 3) (at 47.625 61.595 0)
      (effects (font (size 1.27 1.27)) hide)
    )
    (pin "1")
  )

  (symbol (lib_id "sa800u-baseboard-hw:PWR_FLAG") (at 47.625 69.215 0) (unit 1)
    (in_bom yes) (on_board yes) (fields_autoplaced)
    (property "Reference" "#FLG09" (id 0) (at 47.625 67.31 0)
      (effects (font (size 1.27 1.27)) hide)
    )
    (property "Value" "PWR_FLAG" (id 1) (at 47.625 63.5 0))
    (property "Footprint" "" (id 2) (at 47.625 69.215 0)
      (effects (font (size 1.27 1.27)) hide)
    )
    (property "Datasheet" "~" (id 3) (at 47.625 69.215 0)
      (effects (font (size 1.27 1.27)) hide)
    )
    (pin "1")
  )

  (symbol (lib_id "sa800u-baseboard-hw:L_350n_1.4A_0603") (at 29.337 55.245 0) (unit 1)
    (in_bom yes) (on_board yes) (fields_autoplaced)
    (property "Reference" "L4" (id 0) (at 31.877 49.53 0))
    (property "Value" "L_350n_1.4A_0603" (id 1) (at 43.307 57.785 0)
      (effects (font (size 1.27 1.27) (thickness 0.15)) (justify left bottom) hide)
    )
    (property "Footprint" "sa800u-baseboard-hw-footprints:L_0603_1608Metric" (id 2) (at 43.307 62.865 0)
      (effects (font (size 1.27 1.27) (thickness 0.15)) (justify left bottom) hide)
    )
    (property "Datasheet" "https://pl.mouser.com/datasheet/2/396/wound07_e-1628381.pdf" (id 3) (at 43.307 65.405 0)
      (effects (font (size 1.27 1.27) (thickness 0.15)) (justify left bottom) hide)
    )
    (property "MPN" "BRC1608TR35M" (id 4) (at 43.307 70.485 0)
      (effects (font (size 1.27 1.27) (thickness 0.15)) (justify left bottom) hide)
    )
    (property "Manufacturer" "Taiyo Yuden" (id 5) (at 43.307 67.945 0)
      (effects (font (size 1.27 1.27) (thickness 0.15)) (justify left bottom) hide)
    )
    (property "Val" "350n/1.4A" (id 6) (at 31.877 52.07 0)
      (effects (font (size 1.27 1.27) (thickness 0.15)))
    )
    (property "ISat" "" (id 7) (at 43.307 71.755 0)
      (effects (font (size 1.27 1.27)) (justify left) hide)
    )
    (property "IMax" "" (id 8) (at 43.307 75.565 0)
      (effects (font (size 1.27 1.27) (thickness 0.15)) (justify left bottom) hide)
    )
    (property "Size" "" (id 9) (at 43.307 78.105 0)
      (effects (font (size 1.27 1.27) (thickness 0.15)) (justify left bottom) hide)
    )
    (property "Author" "Antmicro" (id 10) (at 43.307 80.645 0)
      (effects (font (size 1.27 1.27) (thickness 0.15)) (justify left bottom) hide)
    )
    (property "License" "Apache-2.0" (id 11) (at 43.307 83.185 0)
      (effects (font (size 1.27 1.27) (thickness 0.15)) (justify left bottom) hide)
    )
    (pin "1")
    (pin "2")
  )

  (symbol (lib_id "sa800u-baseboard-hw:L_350n_1.4A_0603") (at 29.337 61.595 0) (unit 1)
    (in_bom yes) (on_board yes) (fields_autoplaced)
    (property "Reference" "L5" (id 0) (at 31.877 63.5 0))
    (property "Value" "L_350n_1.4A_0603" (id 1) (at 43.307 64.135 0)
      (effects (font (size 1.27 1.27) (thickness 0.15)) (justify left bottom) hide)
    )
    (property "Footprint" "sa800u-baseboard-hw-footprints:L_0603_1608Metric" (id 2) (at 43.307 69.215 0)
      (effects (font (size 1.27 1.27) (thickness 0.15)) (justify left bottom) hide)
    )
    (property "Datasheet" "https://pl.mouser.com/datasheet/2/396/wound07_e-1628381.pdf" (id 3) (at 43.307 71.755 0)
      (effects (font (size 1.27 1.27) (thickness 0.15)) (justify left bottom) hide)
    )
    (property "MPN" "BRC1608TR35M" (id 4) (at 43.307 76.835 0)
      (effects (font (size 1.27 1.27) (thickness 0.15)) (justify left bottom) hide)
    )
    (property "Manufacturer" "Taiyo Yuden" (id 5) (at 43.307 74.295 0)
      (effects (font (size 1.27 1.27) (thickness 0.15)) (justify left bottom) hide)
    )
    (property "Val" "350n/1.4A" (id 6) (at 31.877 66.04 0)
      (effects (font (size 1.27 1.27) (thickness 0.15)))
    )
    (property "ISat" "" (id 7) (at 43.307 78.105 0)
      (effects (font (size 1.27 1.27)) (justify left) hide)
    )
    (property "IMax" "" (id 8) (at 43.307 81.915 0)
      (effects (font (size 1.27 1.27) (thickness 0.15)) (justify left bottom) hide)
    )
    (property "Size" "" (id 9) (at 43.307 84.455 0)
      (effects (font (size 1.27 1.27) (thickness 0.15)) (justify left bottom) hide)
    )
    (property "Author" "Antmicro" (id 10) (at 43.307 86.995 0)
      (effects (font (size 1.27 1.27) (thickness 0.15)) (justify left bottom) hide)
    )
    (property "License" "Apache-2.0" (id 11) (at 43.307 89.535 0)
      (effects (font (size 1.27 1.27) (thickness 0.15)) (justify left bottom) hide)
    )
    (pin "1")
    (pin "2")
  )

  (symbol (lib_id "sa800u-baseboard-hw:L_350n_1.4A_0603") (at 29.337 69.215 0) (unit 1)
    (in_bom yes) (on_board yes) (fields_autoplaced)
    (property "Reference" "L6" (id 0) (at 31.877 71.12 0))
    (property "Value" "L_350n_1.4A_0603" (id 1) (at 43.307 71.755 0)
      (effects (font (size 1.27 1.27) (thickness 0.15)) (justify left bottom) hide)
    )
    (property "Footprint" "sa800u-baseboard-hw-footprints:L_0603_1608Metric" (id 2) (at 43.307 76.835 0)
      (effects (font (size 1.27 1.27) (thickness 0.15)) (justify left bottom) hide)
    )
    (property "Datasheet" "https://pl.mouser.com/datasheet/2/396/wound07_e-1628381.pdf" (id 3) (at 43.307 79.375 0)
      (effects (font (size 1.27 1.27) (thickness 0.15)) (justify left bottom) hide)
    )
    (property "MPN" "BRC1608TR35M" (id 4) (at 43.307 84.455 0)
      (effects (font (size 1.27 1.27) (thickness 0.15)) (justify left bottom) hide)
    )
    (property "Manufacturer" "Taiyo Yuden" (id 5) (at 43.307 81.915 0)
      (effects (font (size 1.27 1.27) (thickness 0.15)) (justify left bottom) hide)
    )
    (property "Val" "350n/1.4A" (id 6) (at 31.877 73.66 0)
      (effects (font (size 1.27 1.27) (thickness 0.15)))
    )
    (property "ISat" "" (id 7) (at 43.307 85.725 0)
      (effects (font (size 1.27 1.27)) (justify left) hide)
    )
    (property "IMax" "" (id 8) (at 43.307 89.535 0)
      (effects (font (size 1.27 1.27) (thickness 0.15)) (justify left bottom) hide)
    )
    (property "Size" "" (id 9) (at 43.307 92.075 0)
      (effects (font (size 1.27 1.27) (thickness 0.15)) (justify left bottom) hide)
    )
    (property "Author" "Antmicro" (id 10) (at 43.307 94.615 0)
      (effects (font (size 1.27 1.27) (thickness 0.15)) (justify left bottom) hide)
    )
    (property "License" "Apache-2.0" (id 11) (at 43.307 97.155 0)
      (effects (font (size 1.27 1.27) (thickness 0.15)) (justify left bottom) hide)
    )
    (pin "1")
    (pin "2")
  )

  (symbol (lib_id "sa800u-baseboard-hw:C_10u_0402") (at 97.155 27.305 270) (unit 1)
    (in_bom yes) (on_board yes) (fields_autoplaced)
    (property "Reference" "C23" (id 0) (at 100.33 27.3113 90)
      (effects (font (size 1.524 1.524)) (justify left))
    )
    (property "Value" "C_10u_0402" (id 1) (at 93.345 27.305 0)
      (effects (font (size 1.524 1.524)) hide)
    )
    (property "Footprint" "sa800u-baseboard-hw-footprints:C_0402_1005Metric" (id 2) (at 102.235 32.385 0)
      (effects (font (size 1.524 1.524)) (justify left) hide)
    )
    (property "Datasheet" " " (id 3) (at 97.155 27.305 0)
      (effects (font (size 1.27 1.27)) hide)
    )
    (property "Manufacturer" "Yaego" (id 4) (at 107.315 32.385 0)
      (effects (font (size 1.524 1.524)) (justify left) hide)
    )
    (property "MPN" "CC0402MRX5R5BB106" (id 5) (at 104.775 32.385 0)
      (effects (font (size 1.524 1.524)) (justify left) hide)
    )
    (property "Val" "10u" (id 6) (at 100.33 30.4862 90)
      (effects (font (size 1.27 1.27)) (justify left))
    )
    (property "DNP" "DNP" (id 7) (at 100.33 33.0262 90)
      (effects (font (size 1.27 1.27)) (justify left))
    )
    (property "License" "Apache-2.0" (id 8) (at 74.295 47.625 0)
      (effects (font (size 1.27 1.27) (thickness 0.15)) (justify left bottom) hide)
    )
    (property "Author" "Antmicro" (id 9) (at 71.755 47.625 0)
      (effects (font (size 1.27 1.27) (thickness 0.15)) (justify left bottom) hide)
    )
    (property "Voltage" "" (id 10) (at 69.215 47.625 0)
      (effects (font (size 1.27 1.27)) (justify left bottom) hide)
    )
    (property "Dielectric" "" (id 11) (at 66.675 47.625 0)
      (effects (font (size 1.27 1.27)) (justify left bottom) hide)
    )
    (pin "1")
    (pin "2")
  )

  (symbol (lib_id "sa800u-baseboard-hw:C_1u_0402") (at 107.315 27.305 270) (unit 1)
    (in_bom yes) (on_board yes) (fields_autoplaced)
    (property "Reference" "C26" (id 0) (at 110.109 28.5813 90)
      (effects (font (size 1.524 1.524)) (justify left))
    )
    (property "Value" "C_1u_0402" (id 1) (at 103.505 27.305 0)
      (effects (font (size 1.524 1.524)) hide)
    )
    (property "Footprint" "sa800u-baseboard-hw-footprints:C_0402_1005Metric" (id 2) (at 112.395 32.385 0)
      (effects (font (size 1.524 1.524)) (justify left) hide)
    )
    (property "Datasheet" " " (id 3) (at 107.315 27.305 0)
      (effects (font (size 1.27 1.27)) hide)
    )
    (property "Manufacturer" "TDK" (id 4) (at 117.475 32.385 0)
      (effects (font (size 1.524 1.524)) (justify left) hide)
    )
    (property "MPN" "C1005X6S1A105K050BC" (id 5) (at 114.935 32.385 0)
      (effects (font (size 1.524 1.524)) (justify left) hide)
    )
    (property "Val" "1u" (id 6) (at 110.109 31.7562 90)
      (effects (font (size 1.27 1.27)) (justify left))
    )
    (property "License" "Apache-2.0" (id 7) (at 84.455 47.625 0)
      (effects (font (size 1.27 1.27) (thickness 0.15)) (justify left bottom) hide)
    )
    (property "Author" "Antmicro" (id 8) (at 81.915 47.625 0)
      (effects (font (size 1.27 1.27) (thickness 0.15)) (justify left bottom) hide)
    )
    (property "Voltage" "" (id 9) (at 79.375 47.625 0)
      (effects (font (size 1.27 1.27)) (justify left bottom) hide)
    )
    (property "Dielectric" "" (id 10) (at 76.835 47.625 0)
      (effects (font (size 1.27 1.27)) (justify left bottom) hide)
    )
    (pin "1")
    (pin "2")
  )

  (symbol (lib_id "sa800u-baseboard-hw:C_100n_0402") (at 117.475 27.305 270) (unit 1)
    (in_bom yes) (on_board yes) (fields_autoplaced)
    (property "Reference" "C29" (id 0) (at 120.65 28.5813 90)
      (effects (font (size 1.524 1.524)) (justify left))
    )
    (property "Value" "C_100n_0402" (id 1) (at 113.665 27.305 0)
      (effects (font (size 1.524 1.524)) hide)
    )
    (property "Footprint" "sa800u-baseboard-hw-footprints:C_0402_1005Metric" (id 2) (at 122.555 32.385 0)
      (effects (font (size 1.524 1.524)) (justify left) hide)
    )
    (property "Datasheet" "https://search.murata.co.jp/Ceramy/image/img/A01X/G101/ENG/GRM155R61H104KE14-01.pdf" (id 3) (at 117.475 27.305 0)
      (effects (font (size 1.27 1.27)) hide)
    )
    (property "Manufacturer" "Murata" (id 4) (at 127.635 32.385 0)
      (effects (font (size 1.524 1.524)) (justify left) hide)
    )
    (property "MPN" "GRM155R61H104KE14D" (id 5) (at 125.095 32.385 0)
      (effects (font (size 1.524 1.524)) (justify left) hide)
    )
    (property "Val" "100n" (id 6) (at 120.65 31.7562 90)
      (effects (font (size 1.27 1.27)) (justify left))
    )
    (property "License" "Apache-2.0" (id 7) (at 94.615 47.625 0)
      (effects (font (size 1.27 1.27) (thickness 0.15)) (justify left bottom) hide)
    )
    (property "Author" "Antmicro" (id 8) (at 92.075 47.625 0)
      (effects (font (size 1.27 1.27) (thickness 0.15)) (justify left bottom) hide)
    )
    (property "Voltage" "50V" (id 9) (at 89.535 47.625 0)
      (effects (font (size 1.27 1.27)) (justify left bottom) hide)
    )
    (property "Dielectric" "X5R" (id 10) (at 86.995 47.625 0)
      (effects (font (size 1.27 1.27)) (justify left bottom) hide)
    )
    (pin "1")
    (pin "2")
  )

  (symbol (lib_id "sa800u-baseboard-hw:C_100n_0402") (at 127.635 27.305 270) (unit 1)
    (in_bom yes) (on_board yes) (fields_autoplaced)
    (property "Reference" "C32" (id 0) (at 130.81 28.5813 90)
      (effects (font (size 1.524 1.524)) (justify left))
    )
    (property "Value" "C_100n_0402" (id 1) (at 123.825 27.305 0)
      (effects (font (size 1.524 1.524)) hide)
    )
    (property "Footprint" "sa800u-baseboard-hw-footprints:C_0402_1005Metric" (id 2) (at 132.715 32.385 0)
      (effects (font (size 1.524 1.524)) (justify left) hide)
    )
    (property "Datasheet" "https://search.murata.co.jp/Ceramy/image/img/A01X/G101/ENG/GRM155R61H104KE14-01.pdf" (id 3) (at 127.635 27.305 0)
      (effects (font (size 1.27 1.27)) hide)
    )
    (property "Manufacturer" "Murata" (id 4) (at 137.795 32.385 0)
      (effects (font (size 1.524 1.524)) (justify left) hide)
    )
    (property "MPN" "GRM155R61H104KE14D" (id 5) (at 135.255 32.385 0)
      (effects (font (size 1.524 1.524)) (justify left) hide)
    )
    (property "Val" "100n" (id 6) (at 130.81 31.7562 90)
      (effects (font (size 1.27 1.27)) (justify left))
    )
    (property "License" "Apache-2.0" (id 7) (at 104.775 47.625 0)
      (effects (font (size 1.27 1.27) (thickness 0.15)) (justify left bottom) hide)
    )
    (property "Author" "Antmicro" (id 8) (at 102.235 47.625 0)
      (effects (font (size 1.27 1.27) (thickness 0.15)) (justify left bottom) hide)
    )
    (property "Voltage" "50V" (id 9) (at 99.695 47.625 0)
      (effects (font (size 1.27 1.27)) (justify left bottom) hide)
    )
    (property "Dielectric" "X5R" (id 10) (at 97.155 47.625 0)
      (effects (font (size 1.27 1.27)) (justify left bottom) hide)
    )
    (pin "1")
    (pin "2")
  )

  (symbol (lib_id "sa800u-baseboard-hw:C_100n_0402") (at 295.021 180.34 0) (unit 1)
    (in_bom yes) (on_board yes)
    (property "Reference" "C48" (id 0) (at 294.259 178.943 0)
      (effects (font (size 1.524 1.524)))
    )
    (property "Value" "C_100n_0402" (id 1) (at 295.021 184.15 0)
      (effects (font (size 1.524 1.524)) hide)
    )
    (property "Footprint" "sa800u-baseboard-hw-footprints:C_0402_1005Metric" (id 2) (at 300.101 175.26 0)
      (effects (font (size 1.524 1.524)) (justify left) hide)
    )
    (property "Datasheet" "https://search.murata.co.jp/Ceramy/image/img/A01X/G101/ENG/GRM155R61H104KE14-01.pdf" (id 3) (at 295.021 180.34 0)
      (effects (font (size 1.27 1.27)) hide)
    )
    (property "Manufacturer" "Murata" (id 4) (at 300.101 170.18 0)
      (effects (font (size 1.524 1.524)) (justify left) hide)
    )
    (property "MPN" "GRM155R61H104KE14D" (id 5) (at 300.101 172.72 0)
      (effects (font (size 1.524 1.524)) (justify left) hide)
    )
    (property "Val" "100n" (id 6) (at 294.259 181.61 0))
    (property "License" "Apache-2.0" (id 7) (at 315.341 203.2 0)
      (effects (font (size 1.27 1.27) (thickness 0.15)) (justify left bottom) hide)
    )
    (property "Author" "Antmicro" (id 8) (at 315.341 205.74 0)
      (effects (font (size 1.27 1.27) (thickness 0.15)) (justify left bottom) hide)
    )
    (property "Voltage" "50V" (id 9) (at 315.341 208.28 0)
      (effects (font (size 1.27 1.27)) (justify left bottom) hide)
    )
    (property "Dielectric" "X5R" (id 10) (at 315.341 210.82 0)
      (effects (font (size 1.27 1.27)) (justify left bottom) hide)
    )
    (pin "1")
    (pin "2")
  )

  (symbol (lib_id "sa800u-baseboard-hw:C_100n_0402") (at 298.196 185.42 0) (unit 1)
    (in_bom yes) (on_board yes)
    (property "Reference" "C53" (id 0) (at 303.911 184.404 0)
      (effects (font (size 1.524 1.524)))
    )
    (property "Value" "C_100n_0402" (id 1) (at 298.196 189.23 0)
      (effects (font (size 1.524 1.524)) hide)
    )
    (property "Footprint" "sa800u-baseboard-hw-footprints:C_0402_1005Metric" (id 2) (at 303.276 180.34 0)
      (effects (font (size 1.524 1.524)) (justify left) hide)
    )
    (property "Datasheet" "https://search.murata.co.jp/Ceramy/image/img/A01X/G101/ENG/GRM155R61H104KE14-01.pdf" (id 3) (at 298.196 185.42 0)
      (effects (font (size 1.27 1.27)) hide)
    )
    (property "Manufacturer" "Murata" (id 4) (at 303.276 175.26 0)
      (effects (font (size 1.524 1.524)) (justify left) hide)
    )
    (property "MPN" "GRM155R61H104KE14D" (id 5) (at 303.276 177.8 0)
      (effects (font (size 1.524 1.524)) (justify left) hide)
    )
    (property "Val" "100n" (id 6) (at 304.038 187.071 0))
    (property "License" "Apache-2.0" (id 7) (at 318.516 208.28 0)
      (effects (font (size 1.27 1.27) (thickness 0.15)) (justify left bottom) hide)
    )
    (property "Author" "Antmicro" (id 8) (at 318.516 210.82 0)
      (effects (font (size 1.27 1.27) (thickness 0.15)) (justify left bottom) hide)
    )
    (property "Voltage" "50V" (id 9) (at 318.516 213.36 0)
      (effects (font (size 1.27 1.27)) (justify left bottom) hide)
    )
    (property "Dielectric" "X5R" (id 10) (at 318.516 215.9 0)
      (effects (font (size 1.27 1.27)) (justify left bottom) hide)
    )
    (pin "1")
    (pin "2")
  )

  (symbol (lib_id "sa800u-baseboard-hw:C_100n_0402") (at 295.021 187.96 0) (unit 1)
    (in_bom yes) (on_board yes)
    (property "Reference" "C49" (id 0) (at 294.386 186.69 0)
      (effects (font (size 1.524 1.524)))
    )
    (property "Value" "C_100n_0402" (id 1) (at 295.021 191.77 0)
      (effects (font (size 1.524 1.524)) hide)
    )
    (property "Footprint" "sa800u-baseboard-hw-footprints:C_0402_1005Metric" (id 2) (at 300.101 182.88 0)
      (effects (font (size 1.524 1.524)) (justify left) hide)
    )
    (property "Datasheet" "https://search.murata.co.jp/Ceramy/image/img/A01X/G101/ENG/GRM155R61H104KE14-01.pdf" (id 3) (at 295.021 187.96 0)
      (effects (font (size 1.27 1.27)) hide)
    )
    (property "Manufacturer" "Murata" (id 4) (at 300.101 177.8 0)
      (effects (font (size 1.524 1.524)) (justify left) hide)
    )
    (property "MPN" "GRM155R61H104KE14D" (id 5) (at 300.101 180.34 0)
      (effects (font (size 1.524 1.524)) (justify left) hide)
    )
    (property "Val" "100n" (id 6) (at 294.386 189.23 0))
    (property "License" "Apache-2.0" (id 7) (at 315.341 210.82 0)
      (effects (font (size 1.27 1.27) (thickness 0.15)) (justify left bottom) hide)
    )
    (property "Author" "Antmicro" (id 8) (at 315.341 213.36 0)
      (effects (font (size 1.27 1.27) (thickness 0.15)) (justify left bottom) hide)
    )
    (property "Voltage" "50V" (id 9) (at 315.341 215.9 0)
      (effects (font (size 1.27 1.27)) (justify left bottom) hide)
    )
    (property "Dielectric" "X5R" (id 10) (at 315.341 218.44 0)
      (effects (font (size 1.27 1.27)) (justify left bottom) hide)
    )
    (pin "1")
    (pin "2")
  )

  (symbol (lib_id "sa800u-baseboard-hw:R_510R_0402") (at 315.595 191.77 270) (unit 1)
    (in_bom yes) (on_board yes) (fields_autoplaced)
    (property "Reference" "R48" (id 0) (at 317.5 193.04 90)
      (effects (font (size 1.524 1.524)) (justify left))
    )
    (property "Value" "R_510R_0402" (id 1) (at 311.785 191.77 0)
      (effects (font (size 1.524 1.524)) hide)
    )
    (property "Footprint" "sa800u-baseboard-hw-footprints:R_0402_1005Metric" (id 2) (at 320.675 196.85 0)
      (effects (font (size 1.524 1.524)) (justify left) hide)
    )
    (property "Datasheet" "https://www.bourns.com/docs/product-datasheets/cr.pdf" (id 3) (at 315.595 191.77 0)
      (effects (font (size 1.27 1.27)) hide)
    )
    (property "Manufacturer" "Bourns" (id 4) (at 325.755 196.85 0)
      (effects (font (size 1.524 1.524)) (justify left) hide)
    )
    (property "MPN" "CR0402-FX-5100GLF" (id 5) (at 323.215 196.85 0)
      (effects (font (size 1.524 1.524)) (justify left) hide)
    )
    (property "Val" "510R" (id 6) (at 317.5 196.2149 90)
      (effects (font (size 1.27 1.27)) (justify left))
    )
    (property "License" "Apache-2.0" (id 7) (at 290.195 212.09 0)
      (effects (font (size 1.27 1.27) (thickness 0.15)) (justify left bottom) hide)
    )
    (property "Author" "Antmicro" (id 8) (at 287.655 212.09 0)
      (effects (font (size 1.27 1.27) (thickness 0.15)) (justify left bottom) hide)
    )
    (property "Tolerance" "1%" (id 9) (at 305.435 212.09 0)
      (effects (font (size 1.27 1.27)) (justify left bottom) hide)
    )
    (pin "1")
    (pin "2")
  )

  (symbol (lib_id "sa800u-baseboard-hw:GND") (at 127.635 36.195 0) (unit 1)
    (in_bom yes) (on_board yes) (fields_autoplaced)
    (property "Reference" "#PWR022" (id 0) (at 127.635 42.545 0)
      (effects (font (size 1.27 1.27)) hide)
    )
    (property "Value" "GND" (id 1) (at 127.635 40.64 0))
    (property "Footprint" "" (id 2) (at 127.635 36.195 0)
      (effects (font (size 1.27 1.27)) hide)
    )
    (property "Datasheet" "" (id 3) (at 127.635 36.195 0)
      (effects (font (size 1.27 1.27)) hide)
    )
    (property "Author" "Antmicro" (id 4) (at 136.525 43.815 0)
      (effects (font (size 1.27 1.27) (thickness 0.15)) (justify left bottom) hide)
    )
    (property "License" "Apache-2.0" (id 5) (at 136.525 46.355 0)
      (effects (font (size 1.27 1.27) (thickness 0.15)) (justify left bottom) hide)
    )
    (pin "1")
  )

  (symbol (lib_id "sa800u-baseboard-hw:C_10u_0402") (at 154.94 27.305 270) (unit 1)
    (in_bom yes) (on_board yes) (fields_autoplaced)
    (property "Reference" "C38" (id 0) (at 157.48 27.3113 90)
      (effects (font (size 1.524 1.524)) (justify left))
    )
    (property "Value" "C_10u_0402" (id 1) (at 151.13 27.305 0)
      (effects (font (size 1.524 1.524)) hide)
    )
    (property "Footprint" "sa800u-baseboard-hw-footprints:C_0402_1005Metric" (id 2) (at 160.02 32.385 0)
      (effects (font (size 1.524 1.524)) (justify left) hide)
    )
    (property "Datasheet" " " (id 3) (at 154.94 27.305 0)
      (effects (font (size 1.27 1.27)) hide)
    )
    (property "Manufacturer" "Yaego" (id 4) (at 165.1 32.385 0)
      (effects (font (size 1.524 1.524)) (justify left) hide)
    )
    (property "MPN" "CC0402MRX5R5BB106" (id 5) (at 162.56 32.385 0)
      (effects (font (size 1.524 1.524)) (justify left) hide)
    )
    (property "Val" "10u" (id 6) (at 157.48 30.4862 90)
      (effects (font (size 1.27 1.27)) (justify left))
    )
    (property "DNP" "DNP" (id 7) (at 157.48 33.0262 90)
      (effects (font (size 1.27 1.27)) (justify left))
    )
    (property "License" "Apache-2.0" (id 8) (at 132.08 47.625 0)
      (effects (font (size 1.27 1.27) (thickness 0.15)) (justify left bottom) hide)
    )
    (property "Author" "Antmicro" (id 9) (at 129.54 47.625 0)
      (effects (font (size 1.27 1.27) (thickness 0.15)) (justify left bottom) hide)
    )
    (property "Voltage" "" (id 10) (at 127 47.625 0)
      (effects (font (size 1.27 1.27)) (justify left bottom) hide)
    )
    (property "Dielectric" "" (id 11) (at 124.46 47.625 0)
      (effects (font (size 1.27 1.27)) (justify left bottom) hide)
    )
    (pin "1")
    (pin "2")
  )

  (symbol (lib_id "sa800u-baseboard-hw:C_100n_0402") (at 175.26 27.305 270) (unit 1)
    (in_bom yes) (on_board yes) (fields_autoplaced)
    (property "Reference" "C41" (id 0) (at 177.673 28.5813 90)
      (effects (font (size 1.524 1.524)) (justify left))
    )
    (property "Value" "C_100n_0402" (id 1) (at 171.45 27.305 0)
      (effects (font (size 1.524 1.524)) hide)
    )
    (property "Footprint" "sa800u-baseboard-hw-footprints:C_0402_1005Metric" (id 2) (at 180.34 32.385 0)
      (effects (font (size 1.524 1.524)) (justify left) hide)
    )
    (property "Datasheet" "https://search.murata.co.jp/Ceramy/image/img/A01X/G101/ENG/GRM155R61H104KE14-01.pdf" (id 3) (at 175.26 27.305 0)
      (effects (font (size 1.27 1.27)) hide)
    )
    (property "Manufacturer" "Murata" (id 4) (at 185.42 32.385 0)
      (effects (font (size 1.524 1.524)) (justify left) hide)
    )
    (property "MPN" "GRM155R61H104KE14D" (id 5) (at 182.88 32.385 0)
      (effects (font (size 1.524 1.524)) (justify left) hide)
    )
    (property "Val" "100n" (id 6) (at 177.673 31.7562 90)
      (effects (font (size 1.27 1.27)) (justify left))
    )
    (property "License" "Apache-2.0" (id 7) (at 152.4 47.625 0)
      (effects (font (size 1.27 1.27) (thickness 0.15)) (justify left bottom) hide)
    )
    (property "Author" "Antmicro" (id 8) (at 149.86 47.625 0)
      (effects (font (size 1.27 1.27) (thickness 0.15)) (justify left bottom) hide)
    )
    (property "Voltage" "50V" (id 9) (at 147.32 47.625 0)
      (effects (font (size 1.27 1.27)) (justify left bottom) hide)
    )
    (property "Dielectric" "X5R" (id 10) (at 144.78 47.625 0)
      (effects (font (size 1.27 1.27)) (justify left bottom) hide)
    )
    (pin "1")
    (pin "2")
  )

  (symbol (lib_id "sa800u-baseboard-hw:C_100n_0402") (at 185.42 27.305 270) (unit 1)
    (in_bom yes) (on_board yes) (fields_autoplaced)
    (property "Reference" "C42" (id 0) (at 188.087 28.5813 90)
      (effects (font (size 1.524 1.524)) (justify left))
    )
    (property "Value" "C_100n_0402" (id 1) (at 181.61 27.305 0)
      (effects (font (size 1.524 1.524)) hide)
    )
    (property "Footprint" "sa800u-baseboard-hw-footprints:C_0402_1005Metric" (id 2) (at 190.5 32.385 0)
      (effects (font (size 1.524 1.524)) (justify left) hide)
    )
    (property "Datasheet" "https://search.murata.co.jp/Ceramy/image/img/A01X/G101/ENG/GRM155R61H104KE14-01.pdf" (id 3) (at 185.42 27.305 0)
      (effects (font (size 1.27 1.27)) hide)
    )
    (property "Manufacturer" "Murata" (id 4) (at 195.58 32.385 0)
      (effects (font (size 1.524 1.524)) (justify left) hide)
    )
    (property "MPN" "GRM155R61H104KE14D" (id 5) (at 193.04 32.385 0)
      (effects (font (size 1.524 1.524)) (justify left) hide)
    )
    (property "Val" "100n" (id 6) (at 188.087 31.7562 90)
      (effects (font (size 1.27 1.27)) (justify left))
    )
    (property "License" "Apache-2.0" (id 7) (at 162.56 47.625 0)
      (effects (font (size 1.27 1.27) (thickness 0.15)) (justify left bottom) hide)
    )
    (property "Author" "Antmicro" (id 8) (at 160.02 47.625 0)
      (effects (font (size 1.27 1.27) (thickness 0.15)) (justify left bottom) hide)
    )
    (property "Voltage" "50V" (id 9) (at 157.48 47.625 0)
      (effects (font (size 1.27 1.27)) (justify left bottom) hide)
    )
    (property "Dielectric" "X5R" (id 10) (at 154.94 47.625 0)
      (effects (font (size 1.27 1.27)) (justify left bottom) hide)
    )
    (pin "1")
    (pin "2")
  )

  (symbol (lib_id "sa800u-baseboard-hw:GND") (at 185.42 36.195 0) (unit 1)
    (in_bom yes) (on_board yes) (fields_autoplaced)
    (property "Reference" "#PWR027" (id 0) (at 185.42 42.545 0)
      (effects (font (size 1.27 1.27)) hide)
    )
    (property "Value" "GND" (id 1) (at 185.42 40.64 0))
    (property "Footprint" "" (id 2) (at 185.42 36.195 0)
      (effects (font (size 1.27 1.27)) hide)
    )
    (property "Datasheet" "" (id 3) (at 185.42 36.195 0)
      (effects (font (size 1.27 1.27)) hide)
    )
    (property "Author" "Antmicro" (id 4) (at 194.31 43.815 0)
      (effects (font (size 1.27 1.27) (thickness 0.15)) (justify left bottom) hide)
    )
    (property "License" "Apache-2.0" (id 5) (at 194.31 46.355 0)
      (effects (font (size 1.27 1.27) (thickness 0.15)) (justify left bottom) hide)
    )
    (pin "1")
  )

  (symbol (lib_id "sa800u-baseboard-hw:C_100n_0402") (at 165.1 27.305 270) (unit 1)
    (in_bom yes) (on_board yes) (fields_autoplaced)
    (property "Reference" "C40" (id 0) (at 167.64 28.5813 90)
      (effects (font (size 1.524 1.524)) (justify left))
    )
    (property "Value" "C_100n_0402" (id 1) (at 161.29 27.305 0)
      (effects (font (size 1.524 1.524)) hide)
    )
    (property "Footprint" "sa800u-baseboard-hw-footprints:C_0402_1005Metric" (id 2) (at 170.18 32.385 0)
      (effects (font (size 1.524 1.524)) (justify left) hide)
    )
    (property "Datasheet" "https://search.murata.co.jp/Ceramy/image/img/A01X/G101/ENG/GRM155R61H104KE14-01.pdf" (id 3) (at 165.1 27.305 0)
      (effects (font (size 1.27 1.27)) hide)
    )
    (property "Manufacturer" "Murata" (id 4) (at 175.26 32.385 0)
      (effects (font (size 1.524 1.524)) (justify left) hide)
    )
    (property "MPN" "GRM155R61H104KE14D" (id 5) (at 172.72 32.385 0)
      (effects (font (size 1.524 1.524)) (justify left) hide)
    )
    (property "Val" "100n" (id 6) (at 167.64 31.7562 90)
      (effects (font (size 1.27 1.27)) (justify left))
    )
    (property "License" "Apache-2.0" (id 7) (at 142.24 47.625 0)
      (effects (font (size 1.27 1.27) (thickness 0.15)) (justify left bottom) hide)
    )
    (property "Author" "Antmicro" (id 8) (at 139.7 47.625 0)
      (effects (font (size 1.27 1.27) (thickness 0.15)) (justify left bottom) hide)
    )
    (property "Voltage" "50V" (id 9) (at 137.16 47.625 0)
      (effects (font (size 1.27 1.27)) (justify left bottom) hide)
    )
    (property "Dielectric" "X5R" (id 10) (at 134.62 47.625 0)
      (effects (font (size 1.27 1.27)) (justify left bottom) hide)
    )
    (pin "1")
    (pin "2")
  )

  (symbol (lib_id "sa800u-baseboard-hw:C_10u_0402") (at 208.915 27.305 270) (unit 1)
    (in_bom yes) (on_board yes) (fields_autoplaced)
    (property "Reference" "C43" (id 0) (at 212.09 27.3113 90)
      (effects (font (size 1.524 1.524)) (justify left))
    )
    (property "Value" "C_10u_0402" (id 1) (at 205.105 27.305 0)
      (effects (font (size 1.524 1.524)) hide)
    )
    (property "Footprint" "sa800u-baseboard-hw-footprints:C_0402_1005Metric" (id 2) (at 213.995 32.385 0)
      (effects (font (size 1.524 1.524)) (justify left) hide)
    )
    (property "Datasheet" " " (id 3) (at 208.915 27.305 0)
      (effects (font (size 1.27 1.27)) hide)
    )
    (property "Manufacturer" "Yaego" (id 4) (at 219.075 32.385 0)
      (effects (font (size 1.524 1.524)) (justify left) hide)
    )
    (property "MPN" "CC0402MRX5R5BB106" (id 5) (at 216.535 32.385 0)
      (effects (font (size 1.524 1.524)) (justify left) hide)
    )
    (property "Val" "10u" (id 6) (at 212.09 30.4862 90)
      (effects (font (size 1.27 1.27)) (justify left))
    )
    (property "DNP" "DNP" (id 7) (at 212.09 33.0262 90)
      (effects (font (size 1.27 1.27)) (justify left))
    )
    (property "License" "Apache-2.0" (id 8) (at 186.055 47.625 0)
      (effects (font (size 1.27 1.27) (thickness 0.15)) (justify left bottom) hide)
    )
    (property "Author" "Antmicro" (id 9) (at 183.515 47.625 0)
      (effects (font (size 1.27 1.27) (thickness 0.15)) (justify left bottom) hide)
    )
    (property "Voltage" "" (id 10) (at 180.975 47.625 0)
      (effects (font (size 1.27 1.27)) (justify left bottom) hide)
    )
    (property "Dielectric" "" (id 11) (at 178.435 47.625 0)
      (effects (font (size 1.27 1.27)) (justify left bottom) hide)
    )
    (pin "1")
    (pin "2")
  )

  (symbol (lib_id "sa800u-baseboard-hw:GND") (at 219.075 36.195 0) (unit 1)
    (in_bom yes) (on_board yes) (fields_autoplaced)
    (property "Reference" "#PWR029" (id 0) (at 219.075 42.545 0)
      (effects (font (size 1.27 1.27)) hide)
    )
    (property "Value" "GND" (id 1) (at 219.075 40.64 0))
    (property "Footprint" "" (id 2) (at 219.075 36.195 0)
      (effects (font (size 1.27 1.27)) hide)
    )
    (property "Datasheet" "" (id 3) (at 219.075 36.195 0)
      (effects (font (size 1.27 1.27)) hide)
    )
    (property "Author" "Antmicro" (id 4) (at 227.965 43.815 0)
      (effects (font (size 1.27 1.27) (thickness 0.15)) (justify left bottom) hide)
    )
    (property "License" "Apache-2.0" (id 5) (at 227.965 46.355 0)
      (effects (font (size 1.27 1.27) (thickness 0.15)) (justify left bottom) hide)
    )
    (pin "1")
  )

  (symbol (lib_id "sa800u-baseboard-hw:C_100n_0402") (at 219.075 27.305 270) (unit 1)
    (in_bom yes) (on_board yes) (fields_autoplaced)
    (property "Reference" "C45" (id 0) (at 221.996 28.5813 90)
      (effects (font (size 1.524 1.524)) (justify left))
    )
    (property "Value" "C_100n_0402" (id 1) (at 215.265 27.305 0)
      (effects (font (size 1.524 1.524)) hide)
    )
    (property "Footprint" "sa800u-baseboard-hw-footprints:C_0402_1005Metric" (id 2) (at 224.155 32.385 0)
      (effects (font (size 1.524 1.524)) (justify left) hide)
    )
    (property "Datasheet" "https://search.murata.co.jp/Ceramy/image/img/A01X/G101/ENG/GRM155R61H104KE14-01.pdf" (id 3) (at 219.075 27.305 0)
      (effects (font (size 1.27 1.27)) hide)
    )
    (property "Manufacturer" "Murata" (id 4) (at 229.235 32.385 0)
      (effects (font (size 1.524 1.524)) (justify left) hide)
    )
    (property "MPN" "GRM155R61H104KE14D" (id 5) (at 226.695 32.385 0)
      (effects (font (size 1.524 1.524)) (justify left) hide)
    )
    (property "Val" "100n" (id 6) (at 221.996 31.7562 90)
      (effects (font (size 1.27 1.27)) (justify left))
    )
    (property "License" "Apache-2.0" (id 7) (at 196.215 47.625 0)
      (effects (font (size 1.27 1.27) (thickness 0.15)) (justify left bottom) hide)
    )
    (property "Author" "Antmicro" (id 8) (at 193.675 47.625 0)
      (effects (font (size 1.27 1.27) (thickness 0.15)) (justify left bottom) hide)
    )
    (property "Voltage" "50V" (id 9) (at 191.135 47.625 0)
      (effects (font (size 1.27 1.27)) (justify left bottom) hide)
    )
    (property "Dielectric" "X5R" (id 10) (at 188.595 47.625 0)
      (effects (font (size 1.27 1.27)) (justify left bottom) hide)
    )
    (pin "1")
    (pin "2")
  )

  (symbol (lib_id "sa800u-baseboard-hw:R_510R_0402") (at 324.485 191.77 270) (unit 1)
    (in_bom yes) (on_board yes) (fields_autoplaced)
    (property "Reference" "R49" (id 0) (at 326.39 193.04 90)
      (effects (font (size 1.524 1.524)) (justify left))
    )
    (property "Value" "R_510R_0402" (id 1) (at 320.675 191.77 0)
      (effects (font (size 1.524 1.524)) hide)
    )
    (property "Footprint" "sa800u-baseboard-hw-footprints:R_0402_1005Metric" (id 2) (at 329.565 196.85 0)
      (effects (font (size 1.524 1.524)) (justify left) hide)
    )
    (property "Datasheet" "https://www.bourns.com/docs/product-datasheets/cr.pdf" (id 3) (at 324.485 191.77 0)
      (effects (font (size 1.27 1.27)) hide)
    )
    (property "Manufacturer" "Bourns" (id 4) (at 334.645 196.85 0)
      (effects (font (size 1.524 1.524)) (justify left) hide)
    )
    (property "MPN" "CR0402-FX-5100GLF" (id 5) (at 332.105 196.85 0)
      (effects (font (size 1.524 1.524)) (justify left) hide)
    )
    (property "Val" "510R" (id 6) (at 326.39 196.2149 90)
      (effects (font (size 1.27 1.27)) (justify left))
    )
    (property "License" "Apache-2.0" (id 7) (at 299.085 212.09 0)
      (effects (font (size 1.27 1.27) (thickness 0.15)) (justify left bottom) hide)
    )
    (property "Author" "Antmicro" (id 8) (at 296.545 212.09 0)
      (effects (font (size 1.27 1.27) (thickness 0.15)) (justify left bottom) hide)
    )
    (property "Tolerance" "1%" (id 9) (at 314.325 212.09 0)
      (effects (font (size 1.27 1.27)) (justify left bottom) hide)
    )
    (pin "1")
    (pin "2")
  )

  (symbol (lib_id "sa800u-baseboard-hw:R_510R_0402") (at 333.375 191.77 270) (unit 1)
    (in_bom yes) (on_board yes) (fields_autoplaced)
    (property "Reference" "R51" (id 0) (at 335.28 193.04 90)
      (effects (font (size 1.524 1.524)) (justify left))
    )
    (property "Value" "R_510R_0402" (id 1) (at 329.565 191.77 0)
      (effects (font (size 1.524 1.524)) hide)
    )
    (property "Footprint" "sa800u-baseboard-hw-footprints:R_0402_1005Metric" (id 2) (at 338.455 196.85 0)
      (effects (font (size 1.524 1.524)) (justify left) hide)
    )
    (property "Datasheet" "https://www.bourns.com/docs/product-datasheets/cr.pdf" (id 3) (at 333.375 191.77 0)
      (effects (font (size 1.27 1.27)) hide)
    )
    (property "Manufacturer" "Bourns" (id 4) (at 343.535 196.85 0)
      (effects (font (size 1.524 1.524)) (justify left) hide)
    )
    (property "MPN" "CR0402-FX-5100GLF" (id 5) (at 340.995 196.85 0)
      (effects (font (size 1.524 1.524)) (justify left) hide)
    )
    (property "Val" "510R" (id 6) (at 335.28 196.2149 90)
      (effects (font (size 1.27 1.27)) (justify left))
    )
    (property "License" "Apache-2.0" (id 7) (at 307.975 212.09 0)
      (effects (font (size 1.27 1.27) (thickness 0.15)) (justify left bottom) hide)
    )
    (property "Author" "Antmicro" (id 8) (at 305.435 212.09 0)
      (effects (font (size 1.27 1.27) (thickness 0.15)) (justify left bottom) hide)
    )
    (property "Tolerance" "1%" (id 9) (at 323.215 212.09 0)
      (effects (font (size 1.27 1.27)) (justify left bottom) hide)
    )
    (pin "1")
    (pin "2")
  )

  (symbol (lib_id "sa800u-baseboard-hw:R_510R_0402") (at 342.265 191.77 270) (unit 1)
    (in_bom yes) (on_board yes) (fields_autoplaced)
    (property "Reference" "R52" (id 0) (at 344.17 193.04 90)
      (effects (font (size 1.524 1.524)) (justify left))
    )
    (property "Value" "R_510R_0402" (id 1) (at 338.455 191.77 0)
      (effects (font (size 1.524 1.524)) hide)
    )
    (property "Footprint" "sa800u-baseboard-hw-footprints:R_0402_1005Metric" (id 2) (at 347.345 196.85 0)
      (effects (font (size 1.524 1.524)) (justify left) hide)
    )
    (property "Datasheet" "https://www.bourns.com/docs/product-datasheets/cr.pdf" (id 3) (at 342.265 191.77 0)
      (effects (font (size 1.27 1.27)) hide)
    )
    (property "Manufacturer" "Bourns" (id 4) (at 352.425 196.85 0)
      (effects (font (size 1.524 1.524)) (justify left) hide)
    )
    (property "MPN" "CR0402-FX-5100GLF" (id 5) (at 349.885 196.85 0)
      (effects (font (size 1.524 1.524)) (justify left) hide)
    )
    (property "Val" "510R" (id 6) (at 344.17 196.2149 90)
      (effects (font (size 1.27 1.27)) (justify left))
    )
    (property "License" "Apache-2.0" (id 7) (at 316.865 212.09 0)
      (effects (font (size 1.27 1.27) (thickness 0.15)) (justify left bottom) hide)
    )
    (property "Author" "Antmicro" (id 8) (at 314.325 212.09 0)
      (effects (font (size 1.27 1.27) (thickness 0.15)) (justify left bottom) hide)
    )
    (property "Tolerance" "1%" (id 9) (at 332.105 212.09 0)
      (effects (font (size 1.27 1.27)) (justify left bottom) hide)
    )
    (pin "1")
    (pin "2")
  )

  (symbol (lib_id "sa800u-baseboard-hw:R_510R_0402") (at 351.155 191.77 270) (unit 1)
    (in_bom yes) (on_board yes) (fields_autoplaced)
    (property "Reference" "R53" (id 0) (at 353.06 193.04 90)
      (effects (font (size 1.524 1.524)) (justify left))
    )
    (property "Value" "R_510R_0402" (id 1) (at 347.345 191.77 0)
      (effects (font (size 1.524 1.524)) hide)
    )
    (property "Footprint" "sa800u-baseboard-hw-footprints:R_0402_1005Metric" (id 2) (at 356.235 196.85 0)
      (effects (font (size 1.524 1.524)) (justify left) hide)
    )
    (property "Datasheet" "https://www.bourns.com/docs/product-datasheets/cr.pdf" (id 3) (at 351.155 191.77 0)
      (effects (font (size 1.27 1.27)) hide)
    )
    (property "Manufacturer" "Bourns" (id 4) (at 361.315 196.85 0)
      (effects (font (size 1.524 1.524)) (justify left) hide)
    )
    (property "MPN" "CR0402-FX-5100GLF" (id 5) (at 358.775 196.85 0)
      (effects (font (size 1.524 1.524)) (justify left) hide)
    )
    (property "Val" "510R" (id 6) (at 353.06 196.2149 90)
      (effects (font (size 1.27 1.27)) (justify left))
    )
    (property "License" "Apache-2.0" (id 7) (at 325.755 212.09 0)
      (effects (font (size 1.27 1.27) (thickness 0.15)) (justify left bottom) hide)
    )
    (property "Author" "Antmicro" (id 8) (at 323.215 212.09 0)
      (effects (font (size 1.27 1.27) (thickness 0.15)) (justify left bottom) hide)
    )
    (property "Tolerance" "1%" (id 9) (at 340.995 212.09 0)
      (effects (font (size 1.27 1.27)) (justify left bottom) hide)
    )
    (pin "1")
    (pin "2")
  )

  (symbol (lib_id "sa800u-baseboard-hw:R_510R_0402") (at 360.045 191.77 270) (unit 1)
    (in_bom yes) (on_board yes) (fields_autoplaced)
    (property "Reference" "R54" (id 0) (at 361.95 193.04 90)
      (effects (font (size 1.524 1.524)) (justify left))
    )
    (property "Value" "R_510R_0402" (id 1) (at 356.235 191.77 0)
      (effects (font (size 1.524 1.524)) hide)
    )
    (property "Footprint" "sa800u-baseboard-hw-footprints:R_0402_1005Metric" (id 2) (at 365.125 196.85 0)
      (effects (font (size 1.524 1.524)) (justify left) hide)
    )
    (property "Datasheet" "https://www.bourns.com/docs/product-datasheets/cr.pdf" (id 3) (at 360.045 191.77 0)
      (effects (font (size 1.27 1.27)) hide)
    )
    (property "Manufacturer" "Bourns" (id 4) (at 370.205 196.85 0)
      (effects (font (size 1.524 1.524)) (justify left) hide)
    )
    (property "MPN" "CR0402-FX-5100GLF" (id 5) (at 367.665 196.85 0)
      (effects (font (size 1.524 1.524)) (justify left) hide)
    )
    (property "Val" "510R" (id 6) (at 361.95 196.2149 90)
      (effects (font (size 1.27 1.27)) (justify left))
    )
    (property "License" "Apache-2.0" (id 7) (at 334.645 212.09 0)
      (effects (font (size 1.27 1.27) (thickness 0.15)) (justify left bottom) hide)
    )
    (property "Author" "Antmicro" (id 8) (at 332.105 212.09 0)
      (effects (font (size 1.27 1.27) (thickness 0.15)) (justify left bottom) hide)
    )
    (property "Tolerance" "1%" (id 9) (at 349.885 212.09 0)
      (effects (font (size 1.27 1.27)) (justify left bottom) hide)
    )
    (pin "1")
    (pin "2")
  )

  (symbol (lib_id "sa800u-baseboard-hw:R_510R_0402") (at 368.935 191.77 270) (unit 1)
    (in_bom yes) (on_board yes) (fields_autoplaced)
    (property "Reference" "R55" (id 0) (at 370.84 193.04 90)
      (effects (font (size 1.524 1.524)) (justify left))
    )
    (property "Value" "R_510R_0402" (id 1) (at 365.125 191.77 0)
      (effects (font (size 1.524 1.524)) hide)
    )
    (property "Footprint" "sa800u-baseboard-hw-footprints:R_0402_1005Metric" (id 2) (at 374.015 196.85 0)
      (effects (font (size 1.524 1.524)) (justify left) hide)
    )
    (property "Datasheet" "https://www.bourns.com/docs/product-datasheets/cr.pdf" (id 3) (at 368.935 191.77 0)
      (effects (font (size 1.27 1.27)) hide)
    )
    (property "Manufacturer" "Bourns" (id 4) (at 379.095 196.85 0)
      (effects (font (size 1.524 1.524)) (justify left) hide)
    )
    (property "MPN" "CR0402-FX-5100GLF" (id 5) (at 376.555 196.85 0)
      (effects (font (size 1.524 1.524)) (justify left) hide)
    )
    (property "Val" "510R" (id 6) (at 370.84 196.2149 90)
      (effects (font (size 1.27 1.27)) (justify left))
    )
    (property "License" "Apache-2.0" (id 7) (at 343.535 212.09 0)
      (effects (font (size 1.27 1.27) (thickness 0.15)) (justify left bottom) hide)
    )
    (property "Author" "Antmicro" (id 8) (at 340.995 212.09 0)
      (effects (font (size 1.27 1.27) (thickness 0.15)) (justify left bottom) hide)
    )
    (property "Tolerance" "1%" (id 9) (at 358.775 212.09 0)
      (effects (font (size 1.27 1.27)) (justify left bottom) hide)
    )
    (pin "1")
    (pin "2")
  )

  (symbol (lib_id "sa800u-baseboard-hw:R_510R_0402") (at 377.825 191.77 270) (unit 1)
    (in_bom yes) (on_board yes) (fields_autoplaced)
    (property "Reference" "R56" (id 0) (at 379.73 193.04 90)
      (effects (font (size 1.524 1.524)) (justify left))
    )
    (property "Value" "R_510R_0402" (id 1) (at 374.015 191.77 0)
      (effects (font (size 1.524 1.524)) hide)
    )
    (property "Footprint" "sa800u-baseboard-hw-footprints:R_0402_1005Metric" (id 2) (at 382.905 196.85 0)
      (effects (font (size 1.524 1.524)) (justify left) hide)
    )
    (property "Datasheet" "https://www.bourns.com/docs/product-datasheets/cr.pdf" (id 3) (at 377.825 191.77 0)
      (effects (font (size 1.27 1.27)) hide)
    )
    (property "Manufacturer" "Bourns" (id 4) (at 387.985 196.85 0)
      (effects (font (size 1.524 1.524)) (justify left) hide)
    )
    (property "MPN" "CR0402-FX-5100GLF" (id 5) (at 385.445 196.85 0)
      (effects (font (size 1.524 1.524)) (justify left) hide)
    )
    (property "Val" "510R" (id 6) (at 379.73 196.2149 90)
      (effects (font (size 1.27 1.27)) (justify left))
    )
    (property "License" "Apache-2.0" (id 7) (at 352.425 212.09 0)
      (effects (font (size 1.27 1.27) (thickness 0.15)) (justify left bottom) hide)
    )
    (property "Author" "Antmicro" (id 8) (at 349.885 212.09 0)
      (effects (font (size 1.27 1.27) (thickness 0.15)) (justify left bottom) hide)
    )
    (property "Tolerance" "1%" (id 9) (at 367.665 212.09 0)
      (effects (font (size 1.27 1.27)) (justify left bottom) hide)
    )
    (pin "1")
    (pin "2")
  )

  (symbol (lib_id "sa800u-baseboard-hw:R_10k_0402") (at 329.057 212.09 0) (unit 1)
    (in_bom yes) (on_board yes) (fields_autoplaced)
    (property "Reference" "R50" (id 0) (at 331.597 205.74 0)
      (effects (font (size 1.524 1.524)))
    )
    (property "Value" "R_10k_0402" (id 1) (at 329.057 215.9 0)
      (effects (font (size 1.524 1.524)) hide)
    )
    (property "Footprint" "sa800u-baseboard-hw-footprints:R_0402_1005Metric" (id 2) (at 334.137 207.01 0)
      (effects (font (size 1.524 1.524)) (justify left) hide)
    )
    (property "Datasheet" "https://www.bourns.com/docs/product-datasheets/cr.pdf" (id 3) (at 329.057 212.09 0)
      (effects (font (size 1.27 1.27)) hide)
    )
    (property "Manufacturer" "Bourns" (id 4) (at 334.137 201.93 0)
      (effects (font (size 1.524 1.524)) (justify left) hide)
    )
    (property "MPN" "CR0402-FX-1002GLF" (id 5) (at 334.137 204.47 0)
      (effects (font (size 1.524 1.524)) (justify left) hide)
    )
    (property "Val" "10k" (id 6) (at 331.597 208.28 0))
    (property "License" "Apache-2.0" (id 7) (at 349.377 237.49 0)
      (effects (font (size 1.27 1.27) (thickness 0.15)) (justify left bottom) hide)
    )
    (property "Author" "Antmicro" (id 8) (at 349.377 240.03 0)
      (effects (font (size 1.27 1.27) (thickness 0.15)) (justify left bottom) hide)
    )
    (property "Tolerance" "1%" (id 9) (at 349.377 222.25 0)
      (effects (font (size 1.27 1.27)) (justify left bottom) hide)
    )
    (pin "1")
    (pin "2")
  )

  (symbol (lib_id "sa800u-baseboard-hw:GND") (at 342.265 218.567 0) (unit 1)
    (in_bom yes) (on_board yes) (fields_autoplaced)
    (property "Reference" "#PWR035" (id 0) (at 342.265 224.917 0)
      (effects (font (size 1.27 1.27)) hide)
    )
    (property "Value" "GND" (id 1) (at 342.265 223.647 0))
    (property "Footprint" "" (id 2) (at 342.265 218.567 0)
      (effects (font (size 1.27 1.27)) hide)
    )
    (property "Datasheet" "" (id 3) (at 342.265 218.567 0)
      (effects (font (size 1.27 1.27)) hide)
    )
    (property "Author" "Antmicro" (id 4) (at 351.155 226.187 0)
      (effects (font (size 1.27 1.27) (thickness 0.15)) (justify left bottom) hide)
    )
    (property "License" "Apache-2.0" (id 5) (at 351.155 228.727 0)
      (effects (font (size 1.27 1.27) (thickness 0.15)) (justify left bottom) hide)
    )
    (pin "1")
  )

  (symbol (lib_id "sa800u-baseboard-hw:C_100n_0402") (at 361.95 206.121 270) (unit 1)
    (in_bom yes) (on_board yes) (fields_autoplaced)
    (property "Reference" "C55" (id 0) (at 365.379 207.3973 90)
      (effects (font (size 1.524 1.524)) (justify left))
    )
    (property "Value" "C_100n_0402" (id 1) (at 358.14 206.121 0)
      (effects (font (size 1.524 1.524)) hide)
    )
    (property "Footprint" "sa800u-baseboard-hw-footprints:C_0402_1005Metric" (id 2) (at 367.03 211.201 0)
      (effects (font (size 1.524 1.524)) (justify left) hide)
    )
    (property "Datasheet" "https://search.murata.co.jp/Ceramy/image/img/A01X/G101/ENG/GRM155R61H104KE14-01.pdf" (id 3) (at 361.95 206.121 0)
      (effects (font (size 1.27 1.27)) hide)
    )
    (property "Manufacturer" "Murata" (id 4) (at 372.11 211.201 0)
      (effects (font (size 1.524 1.524)) (justify left) hide)
    )
    (property "MPN" "GRM155R61H104KE14D" (id 5) (at 369.57 211.201 0)
      (effects (font (size 1.524 1.524)) (justify left) hide)
    )
    (property "Val" "100n" (id 6) (at 365.379 210.5722 90)
      (effects (font (size 1.27 1.27)) (justify left))
    )
    (property "License" "Apache-2.0" (id 7) (at 339.09 226.441 0)
      (effects (font (size 1.27 1.27) (thickness 0.15)) (justify left bottom) hide)
    )
    (property "Author" "Antmicro" (id 8) (at 336.55 226.441 0)
      (effects (font (size 1.27 1.27) (thickness 0.15)) (justify left bottom) hide)
    )
    (property "Voltage" "50V" (id 9) (at 334.01 226.441 0)
      (effects (font (size 1.27 1.27)) (justify left bottom) hide)
    )
    (property "Dielectric" "X5R" (id 10) (at 331.47 226.441 0)
      (effects (font (size 1.27 1.27)) (justify left bottom) hide)
    )
    (pin "1")
    (pin "2")
  )

  (symbol (lib_id "sa800u-baseboard-hw:C_10p_0402") (at 384.81 207.645 270) (unit 1)
    (in_bom yes) (on_board yes) (fields_autoplaced)
    (property "Reference" "C56" (id 0) (at 381.381 207.6513 90)
      (effects (font (size 1.524 1.524)) (justify right))
    )
    (property "Value" "C_10p_0402" (id 1) (at 381 207.645 0)
      (effects (font (size 1.524 1.524)) hide)
    )
    (property "Footprint" "sa800u-baseboard-hw-footprints:C_0402_1005Metric" (id 2) (at 389.89 212.725 0)
      (effects (font (size 1.524 1.524)) (justify left) hide)
    )
    (property "Datasheet" "https://search.murata.co.jp/Ceramy/image/img/A01X/G101/ENG/GCM1555C1H100GA16-01.pdf" (id 3) (at 384.81 207.645 0)
      (effects (font (size 1.27 1.27)) hide)
    )
    (property "Manufacturer" "Murata" (id 4) (at 394.97 212.725 0)
      (effects (font (size 1.524 1.524)) (justify left) hide)
    )
    (property "MPN" "GCM1555C1H100GA16D" (id 5) (at 392.43 212.725 0)
      (effects (font (size 1.524 1.524)) (justify left) hide)
    )
    (property "Val" "10p" (id 6) (at 381.381 210.8262 90)
      (effects (font (size 1.27 1.27)) (justify right))
    )
    (property "DNP" "DNP" (id 7) (at 381.381 213.3662 90)
      (effects (font (size 1.27 1.27)) (justify right))
    )
    (property "License" "Apache-2.0" (id 8) (at 361.95 227.965 0)
      (effects (font (size 1.27 1.27) (thickness 0.15)) (justify left bottom) hide)
    )
    (property "Author" "Antmicro" (id 9) (at 359.41 227.965 0)
      (effects (font (size 1.27 1.27) (thickness 0.15)) (justify left bottom) hide)
    )
    (property "Voltage" "50V" (id 10) (at 356.87 227.965 0)
      (effects (font (size 1.27 1.27)) (justify left bottom) hide)
    )
    (property "Dielectric" "C0G" (id 11) (at 354.33 227.965 0)
      (effects (font (size 1.27 1.27)) (justify left bottom) hide)
    )
    (pin "1")
    (pin "2")
  )

  (symbol (lib_id "sa800u-baseboard-hw:C_10p_0402") (at 389.89 207.645 270) (unit 1)
    (in_bom yes) (on_board yes) (fields_autoplaced)
    (property "Reference" "C57" (id 0) (at 392.303 207.6513 90)
      (effects (font (size 1.524 1.524)) (justify left))
    )
    (property "Value" "C_10p_0402" (id 1) (at 386.08 207.645 0)
      (effects (font (size 1.524 1.524)) hide)
    )
    (property "Footprint" "sa800u-baseboard-hw-footprints:C_0402_1005Metric" (id 2) (at 394.97 212.725 0)
      (effects (font (size 1.524 1.524)) (justify left) hide)
    )
    (property "Datasheet" "https://search.murata.co.jp/Ceramy/image/img/A01X/G101/ENG/GCM1555C1H100GA16-01.pdf" (id 3) (at 389.89 207.645 0)
      (effects (font (size 1.27 1.27)) hide)
    )
    (property "Manufacturer" "Murata" (id 4) (at 400.05 212.725 0)
      (effects (font (size 1.524 1.524)) (justify left) hide)
    )
    (property "MPN" "GCM1555C1H100GA16D" (id 5) (at 397.51 212.725 0)
      (effects (font (size 1.524 1.524)) (justify left) hide)
    )
    (property "Val" "10p" (id 6) (at 392.303 210.8262 90)
      (effects (font (size 1.27 1.27)) (justify left))
    )
    (property "DNP" "DNP" (id 7) (at 392.303 213.3662 90)
      (effects (font (size 1.27 1.27)) (justify left))
    )
    (property "License" "Apache-2.0" (id 8) (at 367.03 227.965 0)
      (effects (font (size 1.27 1.27) (thickness 0.15)) (justify left bottom) hide)
    )
    (property "Author" "Antmicro" (id 9) (at 364.49 227.965 0)
      (effects (font (size 1.27 1.27) (thickness 0.15)) (justify left bottom) hide)
    )
    (property "Voltage" "50V" (id 10) (at 361.95 227.965 0)
      (effects (font (size 1.27 1.27)) (justify left bottom) hide)
    )
    (property "Dielectric" "C0G" (id 11) (at 359.41 227.965 0)
      (effects (font (size 1.27 1.27)) (justify left bottom) hide)
    )
    (pin "1")
    (pin "2")
  )

  (symbol (lib_id "sa800u-baseboard-hw:GND") (at 384.81 216.535 0) (unit 1)
    (in_bom yes) (on_board yes) (fields_autoplaced)
    (property "Reference" "#PWR038" (id 0) (at 384.81 222.885 0)
      (effects (font (size 1.27 1.27)) hide)
    )
    (property "Value" "GND" (id 1) (at 384.81 220.98 0))
    (property "Footprint" "" (id 2) (at 384.81 216.535 0)
      (effects (font (size 1.27 1.27)) hide)
    )
    (property "Datasheet" "" (id 3) (at 384.81 216.535 0)
      (effects (font (size 1.27 1.27)) hide)
    )
    (property "Author" "Antmicro" (id 4) (at 393.7 224.155 0)
      (effects (font (size 1.27 1.27) (thickness 0.15)) (justify left bottom) hide)
    )
    (property "License" "Apache-2.0" (id 5) (at 393.7 226.695 0)
      (effects (font (size 1.27 1.27) (thickness 0.15)) (justify left bottom) hide)
    )
    (pin "1")
  )

  (symbol (lib_id "sa800u-baseboard-hw:TP_0.75mm_SMD") (at 66.675 31.115 0) (unit 1)
    (in_bom yes) (on_board yes) (fields_autoplaced)
    (property "Reference" "TP10" (id 0) (at 72.39 31.1149 0)
      (effects (font (size 1.27 1.27)) (justify left))
    )
    (property "Value" "TP_0.75mm_SMD" (id 1) (at 66.675 33.655 0)
      (effects (font (size 1.27 1.27)) hide)
    )
    (property "Footprint" "sa800u-baseboard-hw-footprints:TP_SMD_0.75mm" (id 2) (at 71.755 26.035 0)
      (effects (font (size 1.524 1.524)) (justify left) hide)
    )
    (property "Datasheet" "" (id 3) (at 71.755 23.495 0)
      (effects (font (size 1.524 1.524)) (justify left) hide)
    )
    (property "MPN" "" (id 4) (at 84.455 46.355 0)
      (effects (font (size 1.27 1.27) (thickness 0.15)) (justify left bottom) hide)
    )
    (property "Manufacturer" "" (id 5) (at 84.455 48.895 0)
      (effects (font (size 1.27 1.27) (thickness 0.15)) (justify left bottom) hide)
    )
    (property "Author" "Antmicro" (id 6) (at 84.455 51.435 0)
      (effects (font (size 1.27 1.27) (thickness 0.15)) (justify left bottom) hide)
    )
    (property "License" "Apache-2.0" (id 7) (at 84.455 53.975 0)
      (effects (font (size 1.27 1.27) (thickness 0.15)) (justify left bottom) hide)
    )
    (pin "1")
  )

  (symbol (lib_id "sa800u-baseboard-hw:R_1M_0402") (at 69.85 178.435 270) (unit 1)
    (in_bom yes) (on_board yes) (fields_autoplaced)
    (property "Reference" "R21" (id 0) (at 72.39 178.435 90)
      (effects (font (size 1.524 1.524)) (justify left))
    )
    (property "Value" "R_1M_0402" (id 1) (at 66.04 178.435 0)
      (effects (font (size 1.524 1.524)) hide)
    )
    (property "Footprint" "sa800u-baseboard-hw-footprints:R_0402_1005Metric" (id 2) (at 54.61 198.755 0)
      (effects (font (size 1.27 1.27) (thickness 0.15)) (justify left bottom) hide)
    )
    (property "Datasheet" "https://www.bourns.com/docs/product-datasheets/cr.pdf" (id 3) (at 52.07 198.755 0)
      (effects (font (size 1.27 1.27) (thickness 0.15)) (justify left bottom) hide)
    )
    (property "Manufacturer" "Bourns" (id 4) (at 46.99 198.755 0)
      (effects (font (size 1.27 1.27) (thickness 0.15)) (justify left bottom) hide)
    )
    (property "MPN" "CR0402-FX-1004GLF" (id 5) (at 49.53 198.755 0)
      (effects (font (size 1.27 1.27) (thickness 0.15)) (justify left bottom) hide)
    )
    (property "Val" "1M" (id 6) (at 72.39 181.6099 90)
      (effects (font (size 1.27 1.27) (thickness 0.15)) (justify left))
    )
    (property "DNP" "DNP" (id 7) (at 72.39 184.1499 90)
      (effects (font (size 1.27 1.27)) (justify left))
    )
    (property "License" "Apache-2.0" (id 8) (at 44.45 198.755 0)
      (effects (font (size 1.27 1.27) (thickness 0.15)) (justify left bottom) hide)
    )
    (property "Author" "Antmicro" (id 9) (at 41.91 198.755 0)
      (effects (font (size 1.27 1.27) (thickness 0.15)) (justify left bottom) hide)
    )
    (property "Tolerance" "1%" (id 10) (at 59.69 198.755 0)
      (effects (font (size 1.27 1.27)) (justify left bottom) hide)
    )
    (pin "1")
    (pin "2")
  )

  (symbol (lib_id "sa800u-baseboard-hw:TP_0.75mm_SMD") (at 66.675 37.465 0) (unit 1)
    (in_bom yes) (on_board yes) (fields_autoplaced)
    (property "Reference" "TP12" (id 0) (at 71.755 37.4649 0)
      (effects (font (size 1.27 1.27)) (justify left))
    )
    (property "Value" "TP_0.75mm_SMD" (id 1) (at 66.675 40.005 0)
      (effects (font (size 1.27 1.27)) hide)
    )
    (property "Footprint" "sa800u-baseboard-hw-footprints:TP_SMD_0.75mm" (id 2) (at 71.755 32.385 0)
      (effects (font (size 1.524 1.524)) (justify left) hide)
    )
    (property "Datasheet" "" (id 3) (at 71.755 29.845 0)
      (effects (font (size 1.524 1.524)) (justify left) hide)
    )
    (property "MPN" "" (id 4) (at 84.455 52.705 0)
      (effects (font (size 1.27 1.27) (thickness 0.15)) (justify left bottom) hide)
    )
    (property "Manufacturer" "" (id 5) (at 84.455 55.245 0)
      (effects (font (size 1.27 1.27) (thickness 0.15)) (justify left bottom) hide)
    )
    (property "Author" "Antmicro" (id 6) (at 84.455 57.785 0)
      (effects (font (size 1.27 1.27) (thickness 0.15)) (justify left bottom) hide)
    )
    (property "License" "Apache-2.0" (id 7) (at 84.455 60.325 0)
      (effects (font (size 1.27 1.27) (thickness 0.15)) (justify left bottom) hide)
    )
    (pin "1")
  )

  (symbol (lib_id "sa800u-baseboard-hw:TP_0.75mm_SMD") (at 66.421 45.085 0) (unit 1)
    (in_bom yes) (on_board yes) (fields_autoplaced)
    (property "Reference" "TP11" (id 0) (at 72.136 45.0849 0)
      (effects (font (size 1.27 1.27)) (justify left))
    )
    (property "Value" "TP_0.75mm_SMD" (id 1) (at 66.421 47.625 0)
      (effects (font (size 1.27 1.27)) hide)
    )
    (property "Footprint" "sa800u-baseboard-hw-footprints:TP_SMD_0.75mm" (id 2) (at 71.501 40.005 0)
      (effects (font (size 1.524 1.524)) (justify left) hide)
    )
    (property "Datasheet" "" (id 3) (at 71.501 37.465 0)
      (effects (font (size 1.524 1.524)) (justify left) hide)
    )
    (property "MPN" "" (id 4) (at 84.201 60.325 0)
      (effects (font (size 1.27 1.27) (thickness 0.15)) (justify left bottom) hide)
    )
    (property "Manufacturer" "" (id 5) (at 84.201 62.865 0)
      (effects (font (size 1.27 1.27) (thickness 0.15)) (justify left bottom) hide)
    )
    (property "Author" "Antmicro" (id 6) (at 84.201 65.405 0)
      (effects (font (size 1.27 1.27) (thickness 0.15)) (justify left bottom) hide)
    )
    (property "License" "Apache-2.0" (id 7) (at 84.201 67.945 0)
      (effects (font (size 1.27 1.27) (thickness 0.15)) (justify left bottom) hide)
    )
    (pin "1")
  )

  (symbol (lib_id "sa800u-baseboard-hw:TP_0.75mm_SMD") (at 67.31 55.245 0) (unit 1)
    (in_bom yes) (on_board yes) (fields_autoplaced)
    (property "Reference" "TP13" (id 0) (at 72.263 55.2449 0)
      (effects (font (size 1.27 1.27)) (justify left))
    )
    (property "Value" "TP_0.75mm_SMD" (id 1) (at 67.31 57.785 0)
      (effects (font (size 1.27 1.27)) hide)
    )
    (property "Footprint" "sa800u-baseboard-hw-footprints:TP_SMD_0.75mm" (id 2) (at 72.39 50.165 0)
      (effects (font (size 1.524 1.524)) (justify left) hide)
    )
    (property "Datasheet" "" (id 3) (at 72.39 47.625 0)
      (effects (font (size 1.524 1.524)) (justify left) hide)
    )
    (property "MPN" "" (id 4) (at 85.09 70.485 0)
      (effects (font (size 1.27 1.27) (thickness 0.15)) (justify left bottom) hide)
    )
    (property "Manufacturer" "" (id 5) (at 85.09 73.025 0)
      (effects (font (size 1.27 1.27) (thickness 0.15)) (justify left bottom) hide)
    )
    (property "Author" "Antmicro" (id 6) (at 85.09 75.565 0)
      (effects (font (size 1.27 1.27) (thickness 0.15)) (justify left bottom) hide)
    )
    (property "License" "Apache-2.0" (id 7) (at 85.09 78.105 0)
      (effects (font (size 1.27 1.27) (thickness 0.15)) (justify left bottom) hide)
    )
    (pin "1")
  )

  (symbol (lib_id "sa800u-baseboard-hw:TP_0.75mm_SMD") (at 67.31 61.595 0) (unit 1)
    (in_bom yes) (on_board yes) (fields_autoplaced)
    (property "Reference" "TP14" (id 0) (at 72.517 61.5949 0)
      (effects (font (size 1.27 1.27)) (justify left))
    )
    (property "Value" "TP_0.75mm_SMD" (id 1) (at 67.31 64.135 0)
      (effects (font (size 1.27 1.27)) hide)
    )
    (property "Footprint" "sa800u-baseboard-hw-footprints:TP_SMD_0.75mm" (id 2) (at 72.39 56.515 0)
      (effects (font (size 1.524 1.524)) (justify left) hide)
    )
    (property "Datasheet" "" (id 3) (at 72.39 53.975 0)
      (effects (font (size 1.524 1.524)) (justify left) hide)
    )
    (property "MPN" "" (id 4) (at 85.09 76.835 0)
      (effects (font (size 1.27 1.27) (thickness 0.15)) (justify left bottom) hide)
    )
    (property "Manufacturer" "" (id 5) (at 85.09 79.375 0)
      (effects (font (size 1.27 1.27) (thickness 0.15)) (justify left bottom) hide)
    )
    (property "Author" "Antmicro" (id 6) (at 85.09 81.915 0)
      (effects (font (size 1.27 1.27) (thickness 0.15)) (justify left bottom) hide)
    )
    (property "License" "Apache-2.0" (id 7) (at 85.09 84.455 0)
      (effects (font (size 1.27 1.27) (thickness 0.15)) (justify left bottom) hide)
    )
    (pin "1")
  )

  (symbol (lib_id "sa800u-baseboard-hw:GND") (at 321.945 90.17 0) (unit 1)
    (in_bom yes) (on_board yes) (fields_autoplaced)
    (property "Reference" "#PWR034" (id 0) (at 321.945 96.52 0)
      (effects (font (size 1.27 1.27)) hide)
    )
    (property "Value" "GND" (id 1) (at 321.945 94.615 0))
    (property "Footprint" "" (id 2) (at 321.945 90.17 0)
      (effects (font (size 1.27 1.27)) hide)
    )
    (property "Datasheet" "" (id 3) (at 321.945 90.17 0)
      (effects (font (size 1.27 1.27)) hide)
    )
    (property "Author" "Antmicro" (id 4) (at 330.835 97.79 0)
      (effects (font (size 1.27 1.27) (thickness 0.15)) (justify left bottom) hide)
    )
    (property "License" "Apache-2.0" (id 5) (at 330.835 100.33 0)
      (effects (font (size 1.27 1.27) (thickness 0.15)) (justify left bottom) hide)
    )
    (pin "1")
  )

  (symbol (lib_id "sa800u-baseboard-hw:ABM8G-24.000MHZ-18-D2Y-T") (at 60.325 184.785 0) (unit 1)
    (in_bom yes) (on_board yes)
    (property "Reference" "Y2" (id 0) (at 64.135 180.975 0))
    (property "Value" "ABM8G-24.000MHZ-18-D2Y-T" (id 1) (at 51.689 178.689 0))
    (property "Footprint" "sa800u-baseboard-hw-footprints:Oscillator_SMD_Geyer_KX-7-4Pin_3.2x2.5mm" (id 2) (at 60.325 184.785 0)
      (effects (font (size 1.27 1.27)) hide)
    )
    (property "Datasheet" "https://www.farnell.com/datasheets/1883677.pdf" (id 3) (at 60.325 184.785 0)
      (effects (font (size 1.27 1.27)) hide)
    )
    (property "MPN" "ABM8G-24.000MHZ-18-D2Y-T" (id 4) (at 60.325 176.7332 0)
      (effects (font (size 1.27 1.27)) hide)
    )
    (property "Manufacturer" "Abracon" (id 5) (at 60.325 179.0446 0)
      (effects (font (size 1.27 1.27)) hide)
    )
    (property "Val" "24.000MHz" (id 6) (at 84.455 202.565 0)
      (effects (font (size 1.27 1.27) (thickness 0.15)) (justify left bottom) hide)
    )
    (property "Author" "Antmicro" (id 7) (at 84.455 205.105 0)
      (effects (font (size 1.27 1.27) (thickness 0.15)) (justify left bottom) hide)
    )
    (property "License" "Apache-2.0" (id 8) (at 84.455 207.645 0)
      (effects (font (size 1.27 1.27) (thickness 0.15)) (justify left bottom) hide)
    )
    (pin "1")
    (pin "2")
    (pin "3")
    (pin "4")
  )

  (symbol (lib_id "sa800u-baseboard-hw:TP_0.75mm_SMD") (at 67.056 69.215 0) (unit 1)
    (in_bom yes) (on_board yes) (fields_autoplaced)
    (property "Reference" "TP15" (id 0) (at 72.771 69.2149 0)
      (effects (font (size 1.27 1.27)) (justify left))
    )
    (property "Value" "TP_0.75mm_SMD" (id 1) (at 67.056 71.755 0)
      (effects (font (size 1.27 1.27)) hide)
    )
    (property "Footprint" "sa800u-baseboard-hw-footprints:TP_SMD_0.75mm" (id 2) (at 72.136 64.135 0)
      (effects (font (size 1.524 1.524)) (justify left) hide)
    )
    (property "Datasheet" "" (id 3) (at 72.136 61.595 0)
      (effects (font (size 1.524 1.524)) (justify left) hide)
    )
    (property "MPN" "" (id 4) (at 84.836 84.455 0)
      (effects (font (size 1.27 1.27) (thickness 0.15)) (justify left bottom) hide)
    )
    (property "Manufacturer" "" (id 5) (at 84.836 86.995 0)
      (effects (font (size 1.27 1.27) (thickness 0.15)) (justify left bottom) hide)
    )
    (property "Author" "Antmicro" (id 6) (at 84.836 89.535 0)
      (effects (font (size 1.27 1.27) (thickness 0.15)) (justify left bottom) hide)
    )
    (property "License" "Apache-2.0" (id 7) (at 84.836 92.075 0)
      (effects (font (size 1.27 1.27) (thickness 0.15)) (justify left bottom) hide)
    )
    (pin "1")
  )

  (symbol (lib_id "sa800u-baseboard-hw:TP_0.75mm_SMD") (at 154.94 126.365 90) (unit 1)
    (in_bom yes) (on_board yes) (fields_autoplaced)
    (property "Reference" "TP16" (id 0) (at 154.94 119.38 90))
    (property "Value" "TP_0.75mm_SMD" (id 1) (at 157.48 126.365 0)
      (effects (font (size 1.27 1.27)) hide)
    )
    (property "Footprint" "sa800u-baseboard-hw-footprints:TP_SMD_0.75mm" (id 2) (at 149.86 121.285 0)
      (effects (font (size 1.524 1.524)) (justify left) hide)
    )
    (property "Datasheet" "" (id 3) (at 147.32 121.285 0)
      (effects (font (size 1.524 1.524)) (justify left) hide)
    )
    (property "MPN" "" (id 4) (at 170.18 108.585 0)
      (effects (font (size 1.27 1.27) (thickness 0.15)) (justify left bottom) hide)
    )
    (property "Manufacturer" "" (id 5) (at 172.72 108.585 0)
      (effects (font (size 1.27 1.27) (thickness 0.15)) (justify left bottom) hide)
    )
    (property "Author" "Antmicro" (id 6) (at 175.26 108.585 0)
      (effects (font (size 1.27 1.27) (thickness 0.15)) (justify left bottom) hide)
    )
    (property "License" "Apache-2.0" (id 7) (at 177.8 108.585 0)
      (effects (font (size 1.27 1.27) (thickness 0.15)) (justify left bottom) hide)
    )
    (pin "1")
  )

  (symbol (lib_id "sa800u-baseboard-hw:TP_0.75mm_SMD") (at 160.655 126.365 90) (unit 1)
    (in_bom yes) (on_board yes) (fields_autoplaced)
    (property "Reference" "TP19" (id 0) (at 160.655 119.634 90))
    (property "Value" "TP_0.75mm_SMD" (id 1) (at 163.195 126.365 0)
      (effects (font (size 1.27 1.27)) hide)
    )
    (property "Footprint" "sa800u-baseboard-hw-footprints:TP_SMD_0.75mm" (id 2) (at 155.575 121.285 0)
      (effects (font (size 1.524 1.524)) (justify left) hide)
    )
    (property "Datasheet" "" (id 3) (at 153.035 121.285 0)
      (effects (font (size 1.524 1.524)) (justify left) hide)
    )
    (property "MPN" "" (id 4) (at 175.895 108.585 0)
      (effects (font (size 1.27 1.27) (thickness 0.15)) (justify left bottom) hide)
    )
    (property "Manufacturer" "" (id 5) (at 178.435 108.585 0)
      (effects (font (size 1.27 1.27) (thickness 0.15)) (justify left bottom) hide)
    )
    (property "Author" "Antmicro" (id 6) (at 180.975 108.585 0)
      (effects (font (size 1.27 1.27) (thickness 0.15)) (justify left bottom) hide)
    )
    (property "License" "Apache-2.0" (id 7) (at 183.515 108.585 0)
      (effects (font (size 1.27 1.27) (thickness 0.15)) (justify left bottom) hide)
    )
    (pin "1")
  )

  (symbol (lib_name "NFP0QHB242HS2D_2") (lib_id "sa800u-baseboard-hw:NFP0QHB242HS2D") (at 288.925 22.225 0) (unit 1)
    (in_bom yes) (on_board yes)
    (property "Reference" "L7" (id 0) (at 287.147 22.225 0))
    (property "Value" "NFP0QHB242HS2D" (id 1) (at 280.162 24.765 0))
    (property "Footprint" "sa800u-baseboard-hw-footprints:L_Murata_025020_0605Metric" (id 2) (at 282.702 13.843 0)
      (effects (font (size 1.27 1.27)) hide)
    )
    (property "Datasheet" "https://www.farnell.com/datasheets/2616945.pdf" (id 3) (at 288.925 22.225 0)
      (effects (font (size 1.27 1.27)) hide)
    )
    (property "MPN" "NFP0QHB242HS2D" (id 4) (at 288.925 14.1732 0)
      (effects (font (size 1.27 1.27)) hide)
    )
    (property "Manufacturer" "Murata" (id 5) (at 288.925 16.4846 0)
      (effects (font (size 1.27 1.27)) hide)
    )
    (property "Author" "Antmicro" (id 6) (at 320.675 42.545 0)
      (effects (font (size 1.27 1.27) (thickness 0.15)) (justify left bottom) hide)
    )
    (property "License" "Apache-2.0" (id 7) (at 320.675 45.085 0)
      (effects (font (size 1.27 1.27) (thickness 0.15)) (justify left bottom) hide)
    )
    (pin "1")
    (pin "2")
    (pin "3")
    (pin "4")
  )

  (symbol (lib_id "sa800u-baseboard-hw:GND") (at 154.305 60.325 0) (unit 1)
    (in_bom yes) (on_board yes) (fields_autoplaced)
    (property "Reference" "#PWR024" (id 0) (at 154.305 66.675 0)
      (effects (font (size 1.27 1.27)) hide)
    )
    (property "Value" "GND" (id 1) (at 154.305 64.77 0))
    (property "Footprint" "" (id 2) (at 154.305 60.325 0)
      (effects (font (size 1.27 1.27)) hide)
    )
    (property "Datasheet" "" (id 3) (at 154.305 60.325 0)
      (effects (font (size 1.27 1.27)) hide)
    )
    (property "Author" "Antmicro" (id 4) (at 163.195 67.945 0)
      (effects (font (size 1.27 1.27) (thickness 0.15)) (justify left bottom) hide)
    )
    (property "License" "Apache-2.0" (id 5) (at 163.195 70.485 0)
      (effects (font (size 1.27 1.27) (thickness 0.15)) (justify left bottom) hide)
    )
    (pin "1")
  )

  (symbol (lib_name "NFP0QHB242HS2D_3") (lib_id "sa800u-baseboard-hw:NFP0QHB242HS2D") (at 288.925 29.845 0) (unit 1)
    (in_bom yes) (on_board yes)
    (property "Reference" "L8" (id 0) (at 287.147 29.845 0))
    (property "Value" "NFP0QHB242HS2D" (id 1) (at 280.162 32.385 0))
    (property "Footprint" "sa800u-baseboard-hw-footprints:L_Murata_025020_0605Metric" (id 2) (at 282.702 21.463 0)
      (effects (font (size 1.27 1.27)) hide)
    )
    (property "Datasheet" "https://www.farnell.com/datasheets/2616945.pdf" (id 3) (at 288.925 29.845 0)
      (effects (font (size 1.27 1.27)) hide)
    )
    (property "MPN" "NFP0QHB242HS2D" (id 4) (at 288.925 21.7932 0)
      (effects (font (size 1.27 1.27)) hide)
    )
    (property "Manufacturer" "Murata" (id 5) (at 288.925 24.1046 0)
      (effects (font (size 1.27 1.27)) hide)
    )
    (property "Author" "Antmicro" (id 6) (at 320.675 50.165 0)
      (effects (font (size 1.27 1.27) (thickness 0.15)) (justify left bottom) hide)
    )
    (property "License" "Apache-2.0" (id 7) (at 320.675 52.705 0)
      (effects (font (size 1.27 1.27) (thickness 0.15)) (justify left bottom) hide)
    )
    (pin "1")
    (pin "2")
    (pin "3")
    (pin "4")
  )

  (symbol (lib_name "NFP0QHB242HS2D_1") (lib_id "sa800u-baseboard-hw:NFP0QHB242HS2D") (at 288.925 37.465 0) (unit 1)
    (in_bom yes) (on_board yes)
    (property "Reference" "L9" (id 0) (at 287.147 37.465 0))
    (property "Value" "NFP0QHB242HS2D" (id 1) (at 280.162 40.005 0))
    (property "Footprint" "sa800u-baseboard-hw-footprints:L_Murata_025020_0605Metric" (id 2) (at 282.702 29.083 0)
      (effects (font (size 1.27 1.27)) hide)
    )
    (property "Datasheet" "https://www.farnell.com/datasheets/2616945.pdf" (id 3) (at 288.925 37.465 0)
      (effects (font (size 1.27 1.27)) hide)
    )
    (property "MPN" "NFP0QHB242HS2D" (id 4) (at 288.925 29.4132 0)
      (effects (font (size 1.27 1.27)) hide)
    )
    (property "Manufacturer" "Murata" (id 5) (at 288.925 31.7246 0)
      (effects (font (size 1.27 1.27)) hide)
    )
    (property "Author" "Antmicro" (id 6) (at 320.675 57.785 0)
      (effects (font (size 1.27 1.27) (thickness 0.15)) (justify left bottom) hide)
    )
    (property "License" "Apache-2.0" (id 7) (at 320.675 60.325 0)
      (effects (font (size 1.27 1.27) (thickness 0.15)) (justify left bottom) hide)
    )
    (pin "1")
    (pin "2")
    (pin "3")
    (pin "4")
  )

  (symbol (lib_id "sa800u-baseboard-hw:C_10u_0402") (at 93.345 52.07 270) (unit 1)
    (in_bom yes) (on_board yes) (fields_autoplaced)
    (property "Reference" "C22" (id 0) (at 96.266 52.0763 90)
      (effects (font (size 1.524 1.524)) (justify left))
    )
    (property "Value" "C_10u_0402" (id 1) (at 89.535 52.07 0)
      (effects (font (size 1.524 1.524)) hide)
    )
    (property "Footprint" "sa800u-baseboard-hw-footprints:C_0402_1005Metric" (id 2) (at 98.425 57.15 0)
      (effects (font (size 1.524 1.524)) (justify left) hide)
    )
    (property "Datasheet" " " (id 3) (at 93.345 52.07 0)
      (effects (font (size 1.27 1.27)) hide)
    )
    (property "Manufacturer" "Yaego" (id 4) (at 103.505 57.15 0)
      (effects (font (size 1.524 1.524)) (justify left) hide)
    )
    (property "MPN" "CC0402MRX5R5BB106" (id 5) (at 100.965 57.15 0)
      (effects (font (size 1.524 1.524)) (justify left) hide)
    )
    (property "Val" "10u" (id 6) (at 96.266 55.2512 90)
      (effects (font (size 1.27 1.27)) (justify left))
    )
    (property "DNP" "DNP" (id 7) (at 96.266 57.7912 90)
      (effects (font (size 1.27 1.27)) (justify left))
    )
    (property "License" "Apache-2.0" (id 8) (at 70.485 72.39 0)
      (effects (font (size 1.27 1.27) (thickness 0.15)) (justify left bottom) hide)
    )
    (property "Author" "Antmicro" (id 9) (at 67.945 72.39 0)
      (effects (font (size 1.27 1.27) (thickness 0.15)) (justify left bottom) hide)
    )
    (property "Voltage" "" (id 10) (at 65.405 72.39 0)
      (effects (font (size 1.27 1.27)) (justify left bottom) hide)
    )
    (property "Dielectric" "" (id 11) (at 62.865 72.39 0)
      (effects (font (size 1.27 1.27)) (justify left bottom) hide)
    )
    (pin "1")
    (pin "2")
  )

  (symbol (lib_id "sa800u-baseboard-hw:C_1u_0402") (at 103.505 52.07 270) (unit 1)
    (in_bom yes) (on_board yes) (fields_autoplaced)
    (property "Reference" "C25" (id 0) (at 106.68 53.3463 90)
      (effects (font (size 1.524 1.524)) (justify left))
    )
    (property "Value" "C_1u_0402" (id 1) (at 99.695 52.07 0)
      (effects (font (size 1.524 1.524)) hide)
    )
    (property "Footprint" "sa800u-baseboard-hw-footprints:C_0402_1005Metric" (id 2) (at 108.585 57.15 0)
      (effects (font (size 1.524 1.524)) (justify left) hide)
    )
    (property "Datasheet" " " (id 3) (at 103.505 52.07 0)
      (effects (font (size 1.27 1.27)) hide)
    )
    (property "Manufacturer" "TDK" (id 4) (at 113.665 57.15 0)
      (effects (font (size 1.524 1.524)) (justify left) hide)
    )
    (property "MPN" "C1005X6S1A105K050BC" (id 5) (at 111.125 57.15 0)
      (effects (font (size 1.524 1.524)) (justify left) hide)
    )
    (property "Val" "1u" (id 6) (at 106.68 56.5212 90)
      (effects (font (size 1.27 1.27)) (justify left))
    )
    (property "License" "Apache-2.0" (id 7) (at 80.645 72.39 0)
      (effects (font (size 1.27 1.27) (thickness 0.15)) (justify left bottom) hide)
    )
    (property "Author" "Antmicro" (id 8) (at 78.105 72.39 0)
      (effects (font (size 1.27 1.27) (thickness 0.15)) (justify left bottom) hide)
    )
    (property "Voltage" "" (id 9) (at 75.565 72.39 0)
      (effects (font (size 1.27 1.27)) (justify left bottom) hide)
    )
    (property "Dielectric" "" (id 10) (at 73.025 72.39 0)
      (effects (font (size 1.27 1.27)) (justify left bottom) hide)
    )
    (pin "1")
    (pin "2")
  )

  (symbol (lib_id "sa800u-baseboard-hw:C_100n_0402") (at 113.665 52.07 270) (unit 1)
    (in_bom yes) (on_board yes) (fields_autoplaced)
    (property "Reference" "C28" (id 0) (at 117.094 53.3463 90)
      (effects (font (size 1.524 1.524)) (justify left))
    )
    (property "Value" "C_100n_0402" (id 1) (at 109.855 52.07 0)
      (effects (font (size 1.524 1.524)) hide)
    )
    (property "Footprint" "sa800u-baseboard-hw-footprints:C_0402_1005Metric" (id 2) (at 118.745 57.15 0)
      (effects (font (size 1.524 1.524)) (justify left) hide)
    )
    (property "Datasheet" "https://search.murata.co.jp/Ceramy/image/img/A01X/G101/ENG/GRM155R61H104KE14-01.pdf" (id 3) (at 113.665 52.07 0)
      (effects (font (size 1.27 1.27)) hide)
    )
    (property "Manufacturer" "Murata" (id 4) (at 123.825 57.15 0)
      (effects (font (size 1.524 1.524)) (justify left) hide)
    )
    (property "MPN" "GRM155R61H104KE14D" (id 5) (at 121.285 57.15 0)
      (effects (font (size 1.524 1.524)) (justify left) hide)
    )
    (property "Val" "100n" (id 6) (at 117.094 56.5212 90)
      (effects (font (size 1.27 1.27)) (justify left))
    )
    (property "License" "Apache-2.0" (id 7) (at 90.805 72.39 0)
      (effects (font (size 1.27 1.27) (thickness 0.15)) (justify left bottom) hide)
    )
    (property "Author" "Antmicro" (id 8) (at 88.265 72.39 0)
      (effects (font (size 1.27 1.27) (thickness 0.15)) (justify left bottom) hide)
    )
    (property "Voltage" "50V" (id 9) (at 85.725 72.39 0)
      (effects (font (size 1.27 1.27)) (justify left bottom) hide)
    )
    (property "Dielectric" "X5R" (id 10) (at 83.185 72.39 0)
      (effects (font (size 1.27 1.27)) (justify left bottom) hide)
    )
    (pin "1")
    (pin "2")
  )

  (symbol (lib_id "sa800u-baseboard-hw:C_100n_0402") (at 123.825 52.07 270) (unit 1)
    (in_bom yes) (on_board yes) (fields_autoplaced)
    (property "Reference" "C31" (id 0) (at 127.127 53.3463 90)
      (effects (font (size 1.524 1.524)) (justify left))
    )
    (property "Value" "C_100n_0402" (id 1) (at 120.015 52.07 0)
      (effects (font (size 1.524 1.524)) hide)
    )
    (property "Footprint" "sa800u-baseboard-hw-footprints:C_0402_1005Metric" (id 2) (at 128.905 57.15 0)
      (effects (font (size 1.524 1.524)) (justify left) hide)
    )
    (property "Datasheet" "https://search.murata.co.jp/Ceramy/image/img/A01X/G101/ENG/GRM155R61H104KE14-01.pdf" (id 3) (at 123.825 52.07 0)
      (effects (font (size 1.27 1.27)) hide)
    )
    (property "Manufacturer" "Murata" (id 4) (at 133.985 57.15 0)
      (effects (font (size 1.524 1.524)) (justify left) hide)
    )
    (property "MPN" "GRM155R61H104KE14D" (id 5) (at 131.445 57.15 0)
      (effects (font (size 1.524 1.524)) (justify left) hide)
    )
    (property "Val" "100n" (id 6) (at 127.127 56.5212 90)
      (effects (font (size 1.27 1.27)) (justify left))
    )
    (property "License" "Apache-2.0" (id 7) (at 100.965 72.39 0)
      (effects (font (size 1.27 1.27) (thickness 0.15)) (justify left bottom) hide)
    )
    (property "Author" "Antmicro" (id 8) (at 98.425 72.39 0)
      (effects (font (size 1.27 1.27) (thickness 0.15)) (justify left bottom) hide)
    )
    (property "Voltage" "50V" (id 9) (at 95.885 72.39 0)
      (effects (font (size 1.27 1.27)) (justify left bottom) hide)
    )
    (property "Dielectric" "X5R" (id 10) (at 93.345 72.39 0)
      (effects (font (size 1.27 1.27)) (justify left bottom) hide)
    )
    (pin "1")
    (pin "2")
  )

  (symbol (lib_id "sa800u-baseboard-hw:C_100n_0402") (at 133.985 52.07 270) (unit 1)
    (in_bom yes) (on_board yes) (fields_autoplaced)
    (property "Reference" "C33" (id 0) (at 137.287 53.3463 90)
      (effects (font (size 1.524 1.524)) (justify left))
    )
    (property "Value" "C_100n_0402" (id 1) (at 130.175 52.07 0)
      (effects (font (size 1.524 1.524)) hide)
    )
    (property "Footprint" "sa800u-baseboard-hw-footprints:C_0402_1005Metric" (id 2) (at 139.065 57.15 0)
      (effects (font (size 1.524 1.524)) (justify left) hide)
    )
    (property "Datasheet" "https://search.murata.co.jp/Ceramy/image/img/A01X/G101/ENG/GRM155R61H104KE14-01.pdf" (id 3) (at 133.985 52.07 0)
      (effects (font (size 1.27 1.27)) hide)
    )
    (property "Manufacturer" "Murata" (id 4) (at 144.145 57.15 0)
      (effects (font (size 1.524 1.524)) (justify left) hide)
    )
    (property "MPN" "GRM155R61H104KE14D" (id 5) (at 141.605 57.15 0)
      (effects (font (size 1.524 1.524)) (justify left) hide)
    )
    (property "Val" "100n" (id 6) (at 137.287 56.5212 90)
      (effects (font (size 1.27 1.27)) (justify left))
    )
    (property "License" "Apache-2.0" (id 7) (at 111.125 72.39 0)
      (effects (font (size 1.27 1.27) (thickness 0.15)) (justify left bottom) hide)
    )
    (property "Author" "Antmicro" (id 8) (at 108.585 72.39 0)
      (effects (font (size 1.27 1.27) (thickness 0.15)) (justify left bottom) hide)
    )
    (property "Voltage" "50V" (id 9) (at 106.045 72.39 0)
      (effects (font (size 1.27 1.27)) (justify left bottom) hide)
    )
    (property "Dielectric" "X5R" (id 10) (at 103.505 72.39 0)
      (effects (font (size 1.27 1.27)) (justify left bottom) hide)
    )
    (pin "1")
    (pin "2")
  )

  (symbol (lib_id "sa800u-baseboard-hw:C_100n_0402") (at 144.145 52.07 270) (unit 1)
    (in_bom yes) (on_board yes) (fields_autoplaced)
    (property "Reference" "C35" (id 0) (at 147.447 53.3463 90)
      (effects (font (size 1.524 1.524)) (justify left))
    )
    (property "Value" "C_100n_0402" (id 1) (at 140.335 52.07 0)
      (effects (font (size 1.524 1.524)) hide)
    )
    (property "Footprint" "sa800u-baseboard-hw-footprints:C_0402_1005Metric" (id 2) (at 149.225 57.15 0)
      (effects (font (size 1.524 1.524)) (justify left) hide)
    )
    (property "Datasheet" "https://search.murata.co.jp/Ceramy/image/img/A01X/G101/ENG/GRM155R61H104KE14-01.pdf" (id 3) (at 144.145 52.07 0)
      (effects (font (size 1.27 1.27)) hide)
    )
    (property "Manufacturer" "Murata" (id 4) (at 154.305 57.15 0)
      (effects (font (size 1.524 1.524)) (justify left) hide)
    )
    (property "MPN" "GRM155R61H104KE14D" (id 5) (at 151.765 57.15 0)
      (effects (font (size 1.524 1.524)) (justify left) hide)
    )
    (property "Val" "100n" (id 6) (at 147.447 56.5212 90)
      (effects (font (size 1.27 1.27)) (justify left))
    )
    (property "License" "Apache-2.0" (id 7) (at 121.285 72.39 0)
      (effects (font (size 1.27 1.27) (thickness 0.15)) (justify left bottom) hide)
    )
    (property "Author" "Antmicro" (id 8) (at 118.745 72.39 0)
      (effects (font (size 1.27 1.27) (thickness 0.15)) (justify left bottom) hide)
    )
    (property "Voltage" "50V" (id 9) (at 116.205 72.39 0)
      (effects (font (size 1.27 1.27)) (justify left bottom) hide)
    )
    (property "Dielectric" "X5R" (id 10) (at 113.665 72.39 0)
      (effects (font (size 1.27 1.27)) (justify left bottom) hide)
    )
    (pin "1")
    (pin "2")
  )

  (symbol (lib_id "sa800u-baseboard-hw:PUSB3F96X_PASS") (at 363.22 80.01 270) (unit 1)
    (in_bom yes) (on_board yes)
    (property "Reference" "D5" (id 0) (at 350.52 94.234 90)
      (effects (font (size 1.524 1.524)) (justify left))
    )
    (property "Value" "PUSB3F96X_PASS" (id 1) (at 350.52 98.044 90)
      (effects (font (size 1.524 1.524)) (justify left))
    )
    (property "Footprint" "sa800u-baseboard-hw-footprints:Nexperia_DFN-10_2.5x1mm_P0.5mm" (id 2) (at 349.25 85.09 0)
      (effects (font (size 1.524 1.524)) hide)
    )
    (property "Datasheet" "https://pl.mouser.com/datasheet/2/916/PUSB3F96-1600324.pdf" (id 3) (at 363.22 80.01 0)
      (effects (font (size 1.524 1.524)) hide)
    )
    (property "Manufacturer" "Nexperia" (id 4) (at 346.71 85.09 0)
      (effects (font (size 1.27 1.27)) hide)
    )
    (property "MPN" "PUSB3F96X" (id 5) (at 346.71 85.09 0)
      (effects (font (size 1.27 1.27)) hide)
    )
    (property "Author" "Antmicro" (id 6) (at 345.44 105.41 0)
      (effects (font (size 1.27 1.27) (thickness 0.15)) (justify left bottom) hide)
    )
    (property "License" "Apache-2.0" (id 7) (at 342.9 105.41 0)
      (effects (font (size 1.27 1.27) (thickness 0.15)) (justify left bottom) hide)
    )
    (pin "1")
    (pin "10")
    (pin "2")
    (pin "3")
    (pin "4")
    (pin "5")
    (pin "6")
    (pin "7")
    (pin "8")
    (pin "9")
  )

  (symbol (lib_id "sa800u-baseboard-hw:GND") (at 347.345 90.17 0) (unit 1)
    (in_bom yes) (on_board yes) (fields_autoplaced)
    (property "Reference" "#PWR036" (id 0) (at 347.345 96.52 0)
      (effects (font (size 1.27 1.27)) hide)
    )
    (property "Value" "GND" (id 1) (at 347.345 94.615 0))
    (property "Footprint" "" (id 2) (at 347.345 90.17 0)
      (effects (font (size 1.27 1.27)) hide)
    )
    (property "Datasheet" "" (id 3) (at 347.345 90.17 0)
      (effects (font (size 1.27 1.27)) hide)
    )
    (property "Author" "Antmicro" (id 4) (at 356.235 97.79 0)
      (effects (font (size 1.27 1.27) (thickness 0.15)) (justify left bottom) hide)
    )
    (property "License" "Apache-2.0" (id 5) (at 356.235 100.33 0)
      (effects (font (size 1.27 1.27) (thickness 0.15)) (justify left bottom) hide)
    )
    (pin "1")
  )

  (symbol (lib_id "sa800u-baseboard-hw:NFP0QHB242HS2D") (at 288.925 45.085 0) (unit 1)
    (in_bom yes) (on_board yes)
    (property "Reference" "L10" (id 0) (at 287.147 45.085 0))
    (property "Value" "NFP0QHB242HS2D" (id 1) (at 280.162 47.625 0))
    (property "Footprint" "sa800u-baseboard-hw-footprints:L_Murata_025020_0605Metric" (id 2) (at 282.702 36.703 0)
      (effects (font (size 1.27 1.27)) hide)
    )
    (property "Datasheet" "https://www.farnell.com/datasheets/2616945.pdf" (id 3) (at 288.925 45.085 0)
      (effects (font (size 1.27 1.27)) hide)
    )
    (property "MPN" "NFP0QHB242HS2D" (id 4) (at 288.925 37.0332 0)
      (effects (font (size 1.27 1.27)) hide)
    )
    (property "Manufacturer" "Murata" (id 5) (at 288.925 39.3446 0)
      (effects (font (size 1.27 1.27)) hide)
    )
    (property "Author" "Antmicro" (id 6) (at 320.675 65.405 0)
      (effects (font (size 1.27 1.27) (thickness 0.15)) (justify left bottom) hide)
    )
    (property "License" "Apache-2.0" (id 7) (at 320.675 67.945 0)
      (effects (font (size 1.27 1.27) (thickness 0.15)) (justify left bottom) hide)
    )
    (pin "1")
    (pin "2")
    (pin "3")
    (pin "4")
  )

  (symbol (lib_id "sa800u-baseboard-hw:FB_120Z_3A_0603") (at 223.52 74.295 0) (unit 1)
    (in_bom yes) (on_board yes) (fields_autoplaced)
    (property "Reference" "FB2" (id 0) (at 226.0219 67.31 0)
      (effects (font (size 1.524 1.524)))
    )
    (property "Value" "FB_120Z_3A_0603" (id 1) (at 226.0219 71.12 0)
      (effects (font (size 1.524 1.524)))
    )
    (property "Footprint" "sa800u-baseboard-hw-footprints:FB_0603_1608Metric" (id 2) (at 228.6 69.215 0)
      (effects (font (size 1.524 1.524)) (justify left) hide)
    )
    (property "Datasheet" "https://www.murata.com/en-global/api/pdfdownloadapi?cate=luNoiseSupprFilteChipFerriBead&partno=BLM18SG121TN1%23" (id 3) (at 228.6 66.675 0)
      (effects (font (size 1.524 1.524)) (justify left) hide)
    )
    (property "MPN" "BLM18SG121TN1D" (id 4) (at 228.6 61.595 0)
      (effects (font (size 1.524 1.524)) (justify left) hide)
    )
    (property "Manufacturer" "Murata" (id 5) (at 228.6 46.355 0)
      (effects (font (size 1.524 1.524)) (justify left) hide)
    )
    (property "Author" "Antmicro" (id 6) (at 237.49 89.535 0)
      (effects (font (size 1.27 1.27) (thickness 0.15)) (justify left bottom) hide)
    )
    (property "License" "Apache-2.0" (id 7) (at 237.49 92.075 0)
      (effects (font (size 1.27 1.27) (thickness 0.15)) (justify left bottom) hide)
    )
    (pin "1")
    (pin "2")
  )

  (symbol (lib_id "sa800u-baseboard-hw:TP_0.75mm_SMD") (at 189.23 155.575 0) (unit 1)
    (in_bom yes) (on_board yes) (fields_autoplaced)
    (property "Reference" "TP21" (id 0) (at 193.802 155.5749 0)
      (effects (font (size 1.27 1.27)) (justify left))
    )
    (property "Value" "TP_0.75mm_SMD" (id 1) (at 189.23 158.115 0)
      (effects (font (size 1.27 1.27)) hide)
    )
    (property "Footprint" "sa800u-baseboard-hw-footprints:TP_SMD_0.75mm" (id 2) (at 194.31 150.495 0)
      (effects (font (size 1.524 1.524)) (justify left) hide)
    )
    (property "Datasheet" "" (id 3) (at 194.31 147.955 0)
      (effects (font (size 1.524 1.524)) (justify left) hide)
    )
    (property "MPN" "" (id 4) (at 207.01 170.815 0)
      (effects (font (size 1.27 1.27) (thickness 0.15)) (justify left bottom) hide)
    )
    (property "Manufacturer" "" (id 5) (at 207.01 173.355 0)
      (effects (font (size 1.27 1.27) (thickness 0.15)) (justify left bottom) hide)
    )
    (property "Author" "Antmicro" (id 6) (at 207.01 175.895 0)
      (effects (font (size 1.27 1.27) (thickness 0.15)) (justify left bottom) hide)
    )
    (property "License" "Apache-2.0" (id 7) (at 207.01 178.435 0)
      (effects (font (size 1.27 1.27) (thickness 0.15)) (justify left bottom) hide)
    )
    (pin "1")
  )

  (symbol (lib_id "sa800u-baseboard-hw:GND") (at 83.185 190.5 0) (unit 1)
    (in_bom yes) (on_board yes) (fields_autoplaced)
    (property "Reference" "#PWR016" (id 0) (at 83.185 196.85 0)
      (effects (font (size 1.27 1.27)) hide)
    )
    (property "Value" "GND" (id 1) (at 83.185 195.58 0))
    (property "Footprint" "" (id 2) (at 83.185 190.5 0)
      (effects (font (size 1.27 1.27)) hide)
    )
    (property "Datasheet" "" (id 3) (at 83.185 190.5 0)
      (effects (font (size 1.27 1.27)) hide)
    )
    (property "Author" "Antmicro" (id 4) (at 92.075 198.12 0)
      (effects (font (size 1.27 1.27) (thickness 0.15)) (justify left bottom) hide)
    )
    (property "License" "Apache-2.0" (id 5) (at 92.075 200.66 0)
      (effects (font (size 1.27 1.27) (thickness 0.15)) (justify left bottom) hide)
    )
    (pin "1")
  )

  (symbol (lib_id "sa800u-baseboard-hw:GND") (at 64.135 189.865 0) (unit 1)
    (in_bom yes) (on_board yes) (fields_autoplaced)
    (property "Reference" "#PWR013" (id 0) (at 64.135 196.215 0)
      (effects (font (size 1.27 1.27)) hide)
    )
    (property "Value" "GND" (id 1) (at 64.135 194.31 0))
    (property "Footprint" "" (id 2) (at 64.135 189.865 0)
      (effects (font (size 1.27 1.27)) hide)
    )
    (property "Datasheet" "" (id 3) (at 64.135 189.865 0)
      (effects (font (size 1.27 1.27)) hide)
    )
    (property "Author" "Antmicro" (id 4) (at 73.025 197.485 0)
      (effects (font (size 1.27 1.27) (thickness 0.15)) (justify left bottom) hide)
    )
    (property "License" "Apache-2.0" (id 5) (at 73.025 200.025 0)
      (effects (font (size 1.27 1.27) (thickness 0.15)) (justify left bottom) hide)
    )
    (pin "1")
  )

  (symbol (lib_id "sa800u-baseboard-hw:GND") (at 88.265 190.5 0) (unit 1)
    (in_bom yes) (on_board yes) (fields_autoplaced)
    (property "Reference" "#PWR018" (id 0) (at 88.265 196.85 0)
      (effects (font (size 1.27 1.27)) hide)
    )
    (property "Value" "GND" (id 1) (at 88.265 195.58 0))
    (property "Footprint" "" (id 2) (at 88.265 190.5 0)
      (effects (font (size 1.27 1.27)) hide)
    )
    (property "Datasheet" "" (id 3) (at 88.265 190.5 0)
      (effects (font (size 1.27 1.27)) hide)
    )
    (property "Author" "Antmicro" (id 4) (at 97.155 198.12 0)
      (effects (font (size 1.27 1.27) (thickness 0.15)) (justify left bottom) hide)
    )
    (property "License" "Apache-2.0" (id 5) (at 97.155 200.66 0)
      (effects (font (size 1.27 1.27) (thickness 0.15)) (justify left bottom) hide)
    )
    (pin "1")
  )

  (symbol (lib_id "sa800u-baseboard-hw:C_15p_0402") (at 83.185 185.42 270) (unit 1)
    (in_bom yes) (on_board yes) (fields_autoplaced)
    (property "Reference" "C19" (id 0) (at 80.01 186.6963 90)
      (effects (font (size 1.524 1.524)) (justify right))
    )
    (property "Value" "C_15p_0402" (id 1) (at 79.375 185.42 0)
      (effects (font (size 1.524 1.524)) hide)
    )
    (property "Footprint" "sa800u-baseboard-hw-footprints:C_0402_1005Metric" (id 2) (at 88.265 190.5 0)
      (effects (font (size 1.524 1.524)) (justify left) hide)
    )
    (property "Datasheet" " " (id 3) (at 83.185 185.42 0)
      (effects (font (size 1.27 1.27)) hide)
    )
    (property "Manufacturer" "Multicomp" (id 4) (at 93.345 190.5 0)
      (effects (font (size 1.524 1.524)) (justify left) hide)
    )
    (property "MPN" "MC0402N150J500CT" (id 5) (at 90.805 190.5 0)
      (effects (font (size 1.524 1.524)) (justify left) hide)
    )
    (property "Val" "15p" (id 6) (at 80.01 189.8712 90)
      (effects (font (size 1.27 1.27)) (justify right))
    )
    (property "License" "Apache-2.0" (id 7) (at 60.325 205.74 0)
      (effects (font (size 1.27 1.27) (thickness 0.15)) (justify left bottom) hide)
    )
    (property "Author" "Antmicro" (id 8) (at 57.785 205.74 0)
      (effects (font (size 1.27 1.27) (thickness 0.15)) (justify left bottom) hide)
    )
    (property "Voltage" "" (id 9) (at 55.245 205.74 0)
      (effects (font (size 1.27 1.27)) (justify left bottom) hide)
    )
    (property "Dielectric" "" (id 10) (at 52.705 205.74 0)
      (effects (font (size 1.27 1.27)) (justify left bottom) hide)
    )
    (pin "1")
    (pin "2")
  )

  (symbol (lib_id "sa800u-baseboard-hw:C_15p_0402") (at 88.265 185.42 270) (unit 1)
    (in_bom yes) (on_board yes) (fields_autoplaced)
    (property "Reference" "C21" (id 0) (at 91.567 186.6963 90)
      (effects (font (size 1.524 1.524)) (justify left))
    )
    (property "Value" "C_15p_0402" (id 1) (at 84.455 185.42 0)
      (effects (font (size 1.524 1.524)) hide)
    )
    (property "Footprint" "sa800u-baseboard-hw-footprints:C_0402_1005Metric" (id 2) (at 93.345 190.5 0)
      (effects (font (size 1.524 1.524)) (justify left) hide)
    )
    (property "Datasheet" " " (id 3) (at 88.265 185.42 0)
      (effects (font (size 1.27 1.27)) hide)
    )
    (property "Manufacturer" "Multicomp" (id 4) (at 98.425 190.5 0)
      (effects (font (size 1.524 1.524)) (justify left) hide)
    )
    (property "MPN" "MC0402N150J500CT" (id 5) (at 95.885 190.5 0)
      (effects (font (size 1.524 1.524)) (justify left) hide)
    )
    (property "Val" "15p" (id 6) (at 91.567 189.8712 90)
      (effects (font (size 1.27 1.27)) (justify left))
    )
    (property "License" "Apache-2.0" (id 7) (at 65.405 205.74 0)
      (effects (font (size 1.27 1.27) (thickness 0.15)) (justify left bottom) hide)
    )
    (property "Author" "Antmicro" (id 8) (at 62.865 205.74 0)
      (effects (font (size 1.27 1.27) (thickness 0.15)) (justify left bottom) hide)
    )
    (property "Voltage" "" (id 9) (at 60.325 205.74 0)
      (effects (font (size 1.27 1.27)) (justify left bottom) hide)
    )
    (property "Dielectric" "" (id 10) (at 57.785 205.74 0)
      (effects (font (size 1.27 1.27)) (justify left bottom) hide)
    )
    (pin "1")
    (pin "2")
  )

  (symbol (lib_id "sa800u-baseboard-hw:1N4148WS") (at 244.475 74.295 0) (unit 1)
    (in_bom yes) (on_board yes) (fields_autoplaced)
    (property "Reference" "D2" (id 0) (at 248.285 78.74 0)
      (effects (font (size 1.524 1.524)))
    )
    (property "Value" "1N4148WS" (id 1) (at 248.285 82.55 0)
      (effects (font (size 1.524 1.524)))
    )
    (property "Footprint" "sa800u-baseboard-hw-footprints:D_SOD-323F" (id 2) (at 249.555 69.215 0)
      (effects (font (size 1.524 1.524)) (justify left) hide)
    )
    (property "Datasheet" "https://www.onsemi.com/pub/Collateral/1N914BWS-D.pdf" (id 3) (at 249.555 66.675 0)
      (effects (font (size 1.524 1.524)) (justify left) hide)
    )
    (property "MPN" "1N4148WS" (id 4) (at 249.555 61.595 0)
      (effects (font (size 1.524 1.524)) (justify left) hide)
    )
    (property "Manufacturer" "ON Semiconductor" (id 5) (at 249.555 46.355 0)
      (effects (font (size 1.524 1.524)) (justify left) hide)
    )
    (property "Author" "Antmicro" (id 6) (at 266.065 94.615 0)
      (effects (font (size 1.27 1.27) (thickness 0.15)) (justify left bottom) hide)
    )
    (property "License" "Apache-2.0" (id 7) (at 266.065 97.155 0)
      (effects (font (size 1.27 1.27) (thickness 0.15)) (justify left bottom) hide)
    )
    (pin "A")
    (pin "K")
  )

  (symbol (lib_id "sa800u-baseboard-hw:PUSB3F96X_PASS") (at 297.815 93.98 270) (unit 1)
    (in_bom yes) (on_board yes)
    (property "Reference" "D3" (id 0) (at 284.861 108.204 90)
      (effects (font (size 1.524 1.524)) (justify left))
    )
    (property "Value" "PUSB3F96X_PASS" (id 1) (at 284.861 112.014 90)
      (effects (font (size 1.524 1.524)) (justify left))
    )
    (property "Footprint" "sa800u-baseboard-hw-footprints:Nexperia_DFN-10_2.5x1mm_P0.5mm" (id 2) (at 283.845 99.06 0)
      (effects (font (size 1.524 1.524)) hide)
    )
    (property "Datasheet" "https://pl.mouser.com/datasheet/2/916/PUSB3F96-1600324.pdf" (id 3) (at 297.815 93.98 0)
      (effects (font (size 1.524 1.524)) hide)
    )
    (property "Manufacturer" "Nexperia" (id 4) (at 281.305 99.06 0)
      (effects (font (size 1.27 1.27)) hide)
    )
    (property "MPN" "PUSB3F96X" (id 5) (at 281.305 99.06 0)
      (effects (font (size 1.27 1.27)) hide)
    )
    (property "Author" "Antmicro" (id 6) (at 280.035 119.38 0)
      (effects (font (size 1.27 1.27) (thickness 0.15)) (justify left bottom) hide)
    )
    (property "License" "Apache-2.0" (id 7) (at 277.495 119.38 0)
      (effects (font (size 1.27 1.27) (thickness 0.15)) (justify left bottom) hide)
    )
    (pin "1")
    (pin "10")
    (pin "2")
    (pin "3")
    (pin "4")
    (pin "5")
    (pin "6")
    (pin "7")
    (pin "8")
    (pin "9")
  )

  (symbol (lib_id "sa800u-baseboard-hw:TP_0.75mm_SMD") (at 189.23 153.035 0) (unit 1)
    (in_bom yes) (on_board yes) (fields_autoplaced)
    (property "Reference" "TP20" (id 0) (at 194.183 153.0349 0)
      (effects (font (size 1.27 1.27)) (justify left))
    )
    (property "Value" "TP_0.75mm_SMD" (id 1) (at 189.23 155.575 0)
      (effects (font (size 1.27 1.27)) hide)
    )
    (property "Footprint" "sa800u-baseboard-hw-footprints:TP_SMD_0.75mm" (id 2) (at 194.31 147.955 0)
      (effects (font (size 1.524 1.524)) (justify left) hide)
    )
    (property "Datasheet" "" (id 3) (at 194.31 145.415 0)
      (effects (font (size 1.524 1.524)) (justify left) hide)
    )
    (property "MPN" "" (id 4) (at 207.01 168.275 0)
      (effects (font (size 1.27 1.27) (thickness 0.15)) (justify left bottom) hide)
    )
    (property "Manufacturer" "" (id 5) (at 207.01 170.815 0)
      (effects (font (size 1.27 1.27) (thickness 0.15)) (justify left bottom) hide)
    )
    (property "Author" "Antmicro" (id 6) (at 207.01 173.355 0)
      (effects (font (size 1.27 1.27) (thickness 0.15)) (justify left bottom) hide)
    )
    (property "License" "Apache-2.0" (id 7) (at 207.01 175.895 0)
      (effects (font (size 1.27 1.27) (thickness 0.15)) (justify left bottom) hide)
    )
    (pin "1")
  )

  (symbol (lib_id "sa800u-baseboard-hw:TP_0.75mm_SMD") (at 189.484 203.835 0) (unit 1)
    (in_bom yes) (on_board yes) (fields_autoplaced)
    (property "Reference" "TP22" (id 0) (at 194.31 203.8349 0)
      (effects (font (size 1.27 1.27)) (justify left))
    )
    (property "Value" "TP_0.75mm_SMD" (id 1) (at 189.484 206.375 0)
      (effects (font (size 1.27 1.27)) hide)
    )
    (property "Footprint" "sa800u-baseboard-hw-footprints:TP_SMD_0.75mm" (id 2) (at 194.564 198.755 0)
      (effects (font (size 1.524 1.524)) (justify left) hide)
    )
    (property "Datasheet" "" (id 3) (at 194.564 196.215 0)
      (effects (font (size 1.524 1.524)) (justify left) hide)
    )
    (property "MPN" "" (id 4) (at 207.264 219.075 0)
      (effects (font (size 1.27 1.27) (thickness 0.15)) (justify left bottom) hide)
    )
    (property "Manufacturer" "" (id 5) (at 207.264 221.615 0)
      (effects (font (size 1.27 1.27) (thickness 0.15)) (justify left bottom) hide)
    )
    (property "Author" "Antmicro" (id 6) (at 207.264 224.155 0)
      (effects (font (size 1.27 1.27) (thickness 0.15)) (justify left bottom) hide)
    )
    (property "License" "Apache-2.0" (id 7) (at 207.264 226.695 0)
      (effects (font (size 1.27 1.27) (thickness 0.15)) (justify left bottom) hide)
    )
    (pin "1")
  )

  (symbol (lib_id "sa800u-baseboard-hw:TP_0.75mm_SMD") (at 40.005 198.755 180) (unit 1)
    (in_bom yes) (on_board yes) (fields_autoplaced)
    (property "Reference" "TP9" (id 0) (at 36.83 195.326 0))
    (property "Value" "TP_0.75mm_SMD" (id 1) (at 40.005 196.215 0)
      (effects (font (size 1.27 1.27)) hide)
    )
    (property "Footprint" "sa800u-baseboard-hw-footprints:TP_SMD_0.75mm" (id 2) (at 34.925 203.835 0)
      (effects (font (size 1.524 1.524)) (justify left) hide)
    )
    (property "Datasheet" "" (id 3) (at 34.925 206.375 0)
      (effects (font (size 1.524 1.524)) (justify left) hide)
    )
    (property "MPN" "" (id 4) (at 22.225 183.515 0)
      (effects (font (size 1.27 1.27) (thickness 0.15)) (justify left bottom) hide)
    )
    (property "Manufacturer" "" (id 5) (at 22.225 180.975 0)
      (effects (font (size 1.27 1.27) (thickness 0.15)) (justify left bottom) hide)
    )
    (property "Author" "Antmicro" (id 6) (at 22.225 178.435 0)
      (effects (font (size 1.27 1.27) (thickness 0.15)) (justify left bottom) hide)
    )
    (property "License" "Apache-2.0" (id 7) (at 22.225 175.895 0)
      (effects (font (size 1.27 1.27) (thickness 0.15)) (justify left bottom) hide)
    )
    (pin "1")
  )

  (symbol (lib_id "sa800u-baseboard-hw:C_10u_0402") (at 99.06 73.66 270) (unit 1)
    (in_bom yes) (on_board yes) (fields_autoplaced)
    (property "Reference" "C24" (id 0) (at 101.727 73.6663 90)
      (effects (font (size 1.524 1.524)) (justify left))
    )
    (property "Value" "C_10u_0402" (id 1) (at 95.25 73.66 0)
      (effects (font (size 1.524 1.524)) hide)
    )
    (property "Footprint" "sa800u-baseboard-hw-footprints:C_0402_1005Metric" (id 2) (at 104.14 78.74 0)
      (effects (font (size 1.524 1.524)) (justify left) hide)
    )
    (property "Datasheet" " " (id 3) (at 99.06 73.66 0)
      (effects (font (size 1.27 1.27)) hide)
    )
    (property "Manufacturer" "Yaego" (id 4) (at 109.22 78.74 0)
      (effects (font (size 1.524 1.524)) (justify left) hide)
    )
    (property "MPN" "CC0402MRX5R5BB106" (id 5) (at 106.68 78.74 0)
      (effects (font (size 1.524 1.524)) (justify left) hide)
    )
    (property "Val" "10u" (id 6) (at 101.727 76.8412 90)
      (effects (font (size 1.27 1.27)) (justify left))
    )
    (property "DNP" "DNP" (id 7) (at 101.727 79.3812 90)
      (effects (font (size 1.27 1.27)) (justify left))
    )
    (property "License" "Apache-2.0" (id 8) (at 76.2 93.98 0)
      (effects (font (size 1.27 1.27) (thickness 0.15)) (justify left bottom) hide)
    )
    (property "Author" "Antmicro" (id 9) (at 73.66 93.98 0)
      (effects (font (size 1.27 1.27) (thickness 0.15)) (justify left bottom) hide)
    )
    (property "Voltage" "" (id 10) (at 71.12 93.98 0)
      (effects (font (size 1.27 1.27)) (justify left bottom) hide)
    )
    (property "Dielectric" "" (id 11) (at 68.58 93.98 0)
      (effects (font (size 1.27 1.27)) (justify left bottom) hide)
    )
    (pin "1")
    (pin "2")
  )

  (symbol (lib_id "sa800u-baseboard-hw:GND") (at 119.38 82.55 0) (unit 1)
    (in_bom yes) (on_board yes) (fields_autoplaced)
    (property "Reference" "#PWR021" (id 0) (at 119.38 88.9 0)
      (effects (font (size 1.27 1.27)) hide)
    )
    (property "Value" "GND" (id 1) (at 119.38 87.63 0))
    (property "Footprint" "" (id 2) (at 119.38 82.55 0)
      (effects (font (size 1.27 1.27)) hide)
    )
    (property "Datasheet" "" (id 3) (at 119.38 82.55 0)
      (effects (font (size 1.27 1.27)) hide)
    )
    (property "Author" "Antmicro" (id 4) (at 128.27 90.17 0)
      (effects (font (size 1.27 1.27) (thickness 0.15)) (justify left bottom) hide)
    )
    (property "License" "Apache-2.0" (id 5) (at 128.27 92.71 0)
      (effects (font (size 1.27 1.27) (thickness 0.15)) (justify left bottom) hide)
    )
    (pin "1")
  )

  (symbol (lib_id "sa800u-baseboard-hw:C_100n_0402") (at 109.22 73.66 270) (unit 1)
    (in_bom yes) (on_board yes) (fields_autoplaced)
    (property "Reference" "C27" (id 0) (at 111.76 74.9363 90)
      (effects (font (size 1.524 1.524)) (justify left))
    )
    (property "Value" "C_100n_0402" (id 1) (at 105.41 73.66 0)
      (effects (font (size 1.524 1.524)) hide)
    )
    (property "Footprint" "sa800u-baseboard-hw-footprints:C_0402_1005Metric" (id 2) (at 114.3 78.74 0)
      (effects (font (size 1.524 1.524)) (justify left) hide)
    )
    (property "Datasheet" "https://search.murata.co.jp/Ceramy/image/img/A01X/G101/ENG/GRM155R61H104KE14-01.pdf" (id 3) (at 109.22 73.66 0)
      (effects (font (size 1.27 1.27)) hide)
    )
    (property "Manufacturer" "Murata" (id 4) (at 119.38 78.74 0)
      (effects (font (size 1.524 1.524)) (justify left) hide)
    )
    (property "MPN" "GRM155R61H104KE14D" (id 5) (at 116.84 78.74 0)
      (effects (font (size 1.524 1.524)) (justify left) hide)
    )
    (property "Val" "100n" (id 6) (at 111.76 78.1112 90)
      (effects (font (size 1.27 1.27)) (justify left))
    )
    (property "License" "Apache-2.0" (id 7) (at 86.36 93.98 0)
      (effects (font (size 1.27 1.27) (thickness 0.15)) (justify left bottom) hide)
    )
    (property "Author" "Antmicro" (id 8) (at 83.82 93.98 0)
      (effects (font (size 1.27 1.27) (thickness 0.15)) (justify left bottom) hide)
    )
    (property "Voltage" "50V" (id 9) (at 81.28 93.98 0)
      (effects (font (size 1.27 1.27)) (justify left bottom) hide)
    )
    (property "Dielectric" "X5R" (id 10) (at 78.74 93.98 0)
      (effects (font (size 1.27 1.27)) (justify left bottom) hide)
    )
    (pin "1")
    (pin "2")
  )

  (symbol (lib_id "sa800u-baseboard-hw:TP_0.75mm_SMD") (at 200.66 267.335 0) (unit 1)
    (in_bom yes) (on_board yes) (fields_autoplaced)
    (property "Reference" "TP18" (id 0) (at 205.613 267.3349 0)
      (effects (font (size 1.27 1.27)) (justify left))
    )
    (property "Value" "TP_0.75mm_SMD" (id 1) (at 200.66 269.875 0)
      (effects (font (size 1.27 1.27)) hide)
    )
    (property "Footprint" "sa800u-baseboard-hw-footprints:TP_SMD_0.75mm" (id 2) (at 205.74 262.255 0)
      (effects (font (size 1.524 1.524)) (justify left) hide)
    )
    (property "Datasheet" "" (id 3) (at 205.74 259.715 0)
      (effects (font (size 1.524 1.524)) (justify left) hide)
    )
    (property "MPN" "" (id 4) (at 218.44 282.575 0)
      (effects (font (size 1.27 1.27) (thickness 0.15)) (justify left bottom) hide)
    )
    (property "Manufacturer" "" (id 5) (at 218.44 285.115 0)
      (effects (font (size 1.27 1.27) (thickness 0.15)) (justify left bottom) hide)
    )
    (property "Author" "Antmicro" (id 6) (at 218.44 287.655 0)
      (effects (font (size 1.27 1.27) (thickness 0.15)) (justify left bottom) hide)
    )
    (property "License" "Apache-2.0" (id 7) (at 218.44 290.195 0)
      (effects (font (size 1.27 1.27) (thickness 0.15)) (justify left bottom) hide)
    )
    (pin "1")
  )

  (symbol (lib_id "sa800u-baseboard-hw:C_100n_0402") (at 119.38 73.66 270) (unit 1)
    (in_bom yes) (on_board yes) (fields_autoplaced)
    (property "Reference" "C30" (id 0) (at 121.92 74.9363 90)
      (effects (font (size 1.524 1.524)) (justify left))
    )
    (property "Value" "C_100n_0402" (id 1) (at 115.57 73.66 0)
      (effects (font (size 1.524 1.524)) hide)
    )
    (property "Footprint" "sa800u-baseboard-hw-footprints:C_0402_1005Metric" (id 2) (at 124.46 78.74 0)
      (effects (font (size 1.524 1.524)) (justify left) hide)
    )
    (property "Datasheet" "https://search.murata.co.jp/Ceramy/image/img/A01X/G101/ENG/GRM155R61H104KE14-01.pdf" (id 3) (at 119.38 73.66 0)
      (effects (font (size 1.27 1.27)) hide)
    )
    (property "Manufacturer" "Murata" (id 4) (at 129.54 78.74 0)
      (effects (font (size 1.524 1.524)) (justify left) hide)
    )
    (property "MPN" "GRM155R61H104KE14D" (id 5) (at 127 78.74 0)
      (effects (font (size 1.524 1.524)) (justify left) hide)
    )
    (property "Val" "100n" (id 6) (at 121.92 78.1112 90)
      (effects (font (size 1.27 1.27)) (justify left))
    )
    (property "License" "Apache-2.0" (id 7) (at 96.52 93.98 0)
      (effects (font (size 1.27 1.27) (thickness 0.15)) (justify left bottom) hide)
    )
    (property "Author" "Antmicro" (id 8) (at 93.98 93.98 0)
      (effects (font (size 1.27 1.27) (thickness 0.15)) (justify left bottom) hide)
    )
    (property "Voltage" "50V" (id 9) (at 91.44 93.98 0)
      (effects (font (size 1.27 1.27)) (justify left bottom) hide)
    )
    (property "Dielectric" "X5R" (id 10) (at 88.9 93.98 0)
      (effects (font (size 1.27 1.27)) (justify left bottom) hide)
    )
    (pin "1")
    (pin "2")
  )

  (symbol (lib_id "sa800u-baseboard-hw:R_7k68_0402") (at 91.821 202.692 270) (unit 1)
    (in_bom yes) (on_board yes) (fields_autoplaced)
    (property "Reference" "R22" (id 0) (at 89.916 203.962 90)
      (effects (font (size 1.524 1.524)) (justify right))
    )
    (property "Value" "R_7k68_0402" (id 1) (at 88.011 202.692 0)
      (effects (font (size 1.524 1.524)) hide)
    )
    (property "Footprint" "sa800u-baseboard-hw-footprints:R_0402_1005Metric" (id 2) (at 96.901 207.772 0)
      (effects (font (size 1.524 1.524)) (justify left) hide)
    )
    (property "Datasheet" "https://www.bourns.com/docs/product-datasheets/cr.pdf" (id 3) (at 91.821 202.692 0)
      (effects (font (size 1.27 1.27)) hide)
    )
    (property "Manufacturer" "Bourns" (id 4) (at 101.981 207.772 0)
      (effects (font (size 1.524 1.524)) (justify left) hide)
    )
    (property "MPN" "CR0402-FX-7681GLF" (id 5) (at 99.441 207.772 0)
      (effects (font (size 1.524 1.524)) (justify left) hide)
    )
    (property "Val" "7k68" (id 6) (at 89.916 207.1369 90)
      (effects (font (size 1.27 1.27)) (justify right))
    )
    (property "License" "Apache-2.0" (id 7) (at 66.421 223.012 0)
      (effects (font (size 1.27 1.27) (thickness 0.15)) (justify left bottom) hide)
    )
    (property "Author" "Antmicro" (id 8) (at 63.881 223.012 0)
      (effects (font (size 1.27 1.27) (thickness 0.15)) (justify left bottom) hide)
    )
    (property "Tolerance" "1%" (id 9) (at 81.661 223.012 0)
      (effects (font (size 1.27 1.27)) (justify left bottom) hide)
    )
    (pin "1")
    (pin "2")
  )

  (symbol (lib_id "sa800u-baseboard-hw:TP_0.75mm_SMD") (at 200.66 246.38 0) (unit 1)
    (in_bom yes) (on_board yes)
    (property "Reference" "TP17" (id 0) (at 204.978 246.38 0)
      (effects (font (size 1.27 1.27)) (justify left))
    )
    (property "Value" "TP_0.75mm_SMD" (id 1) (at 200.66 248.92 0)
      (effects (font (size 1.27 1.27)) hide)
    )
    (property "Footprint" "sa800u-baseboard-hw-footprints:TP_SMD_0.75mm" (id 2) (at 205.74 241.3 0)
      (effects (font (size 1.524 1.524)) (justify left) hide)
    )
    (property "Datasheet" "" (id 3) (at 205.74 238.76 0)
      (effects (font (size 1.524 1.524)) (justify left) hide)
    )
    (property "MPN" "" (id 4) (at 218.44 261.62 0)
      (effects (font (size 1.27 1.27) (thickness 0.15)) (justify left bottom) hide)
    )
    (property "Manufacturer" "" (id 5) (at 218.44 264.16 0)
      (effects (font (size 1.27 1.27) (thickness 0.15)) (justify left bottom) hide)
    )
    (property "Author" "Antmicro" (id 6) (at 218.44 266.7 0)
      (effects (font (size 1.27 1.27) (thickness 0.15)) (justify left bottom) hide)
    )
    (property "License" "Apache-2.0" (id 7) (at 218.44 269.24 0)
      (effects (font (size 1.27 1.27) (thickness 0.15)) (justify left bottom) hide)
    )
    (pin "1")
  )

  (symbol (lib_id "sa800u-baseboard-hw:C_10u_0402") (at 146.685 73.66 270) (unit 1)
    (in_bom yes) (on_board yes) (fields_autoplaced)
    (property "Reference" "C36" (id 0) (at 149.86 73.6663 90)
      (effects (font (size 1.524 1.524)) (justify left))
    )
    (property "Value" "C_10u_0402" (id 1) (at 142.875 73.66 0)
      (effects (font (size 1.524 1.524)) hide)
    )
    (property "Footprint" "sa800u-baseboard-hw-footprints:C_0402_1005Metric" (id 2) (at 151.765 78.74 0)
      (effects (font (size 1.524 1.524)) (justify left) hide)
    )
    (property "Datasheet" " " (id 3) (at 146.685 73.66 0)
      (effects (font (size 1.27 1.27)) hide)
    )
    (property "Manufacturer" "Yaego" (id 4) (at 156.845 78.74 0)
      (effects (font (size 1.524 1.524)) (justify left) hide)
    )
    (property "MPN" "CC0402MRX5R5BB106" (id 5) (at 154.305 78.74 0)
      (effects (font (size 1.524 1.524)) (justify left) hide)
    )
    (property "Val" "10u" (id 6) (at 149.86 76.8412 90)
      (effects (font (size 1.27 1.27)) (justify left))
    )
    (property "DNP" "DNP" (id 7) (at 149.86 79.3812 90)
      (effects (font (size 1.27 1.27)) (justify left))
    )
    (property "License" "Apache-2.0" (id 8) (at 123.825 93.98 0)
      (effects (font (size 1.27 1.27) (thickness 0.15)) (justify left bottom) hide)
    )
    (property "Author" "Antmicro" (id 9) (at 121.285 93.98 0)
      (effects (font (size 1.27 1.27) (thickness 0.15)) (justify left bottom) hide)
    )
    (property "Voltage" "" (id 10) (at 118.745 93.98 0)
      (effects (font (size 1.27 1.27)) (justify left bottom) hide)
    )
    (property "Dielectric" "" (id 11) (at 116.205 93.98 0)
      (effects (font (size 1.27 1.27)) (justify left bottom) hide)
    )
    (pin "1")
    (pin "2")
  )

  (symbol (lib_id "sa800u-baseboard-hw:GND") (at 156.845 82.55 0) (unit 1)
    (in_bom yes) (on_board yes) (fields_autoplaced)
    (property "Reference" "#PWR025" (id 0) (at 156.845 88.9 0)
      (effects (font (size 1.27 1.27)) hide)
    )
    (property "Value" "GND" (id 1) (at 156.845 87.63 0))
    (property "Footprint" "" (id 2) (at 156.845 82.55 0)
      (effects (font (size 1.27 1.27)) hide)
    )
    (property "Datasheet" "" (id 3) (at 156.845 82.55 0)
      (effects (font (size 1.27 1.27)) hide)
    )
    (property "Author" "Antmicro" (id 4) (at 165.735 90.17 0)
      (effects (font (size 1.27 1.27) (thickness 0.15)) (justify left bottom) hide)
    )
    (property "License" "Apache-2.0" (id 5) (at 165.735 92.71 0)
      (effects (font (size 1.27 1.27) (thickness 0.15)) (justify left bottom) hide)
    )
    (pin "1")
  )

  (symbol (lib_id "sa800u-baseboard-hw:C_100n_0402") (at 156.845 73.66 270) (unit 1)
    (in_bom yes) (on_board yes) (fields_autoplaced)
    (property "Reference" "C39" (id 0) (at 159.893 74.9363 90)
      (effects (font (size 1.524 1.524)) (justify left))
    )
    (property "Value" "C_100n_0402" (id 1) (at 153.035 73.66 0)
      (effects (font (size 1.524 1.524)) hide)
    )
    (property "Footprint" "sa800u-baseboard-hw-footprints:C_0402_1005Metric" (id 2) (at 161.925 78.74 0)
      (effects (font (size 1.524 1.524)) (justify left) hide)
    )
    (property "Datasheet" "https://search.murata.co.jp/Ceramy/image/img/A01X/G101/ENG/GRM155R61H104KE14-01.pdf" (id 3) (at 156.845 73.66 0)
      (effects (font (size 1.27 1.27)) hide)
    )
    (property "Manufacturer" "Murata" (id 4) (at 167.005 78.74 0)
      (effects (font (size 1.524 1.524)) (justify left) hide)
    )
    (property "MPN" "GRM155R61H104KE14D" (id 5) (at 164.465 78.74 0)
      (effects (font (size 1.524 1.524)) (justify left) hide)
    )
    (property "Val" "100n" (id 6) (at 159.893 78.1112 90)
      (effects (font (size 1.27 1.27)) (justify left))
    )
    (property "License" "Apache-2.0" (id 7) (at 133.985 93.98 0)
      (effects (font (size 1.27 1.27) (thickness 0.15)) (justify left bottom) hide)
    )
    (property "Author" "Antmicro" (id 8) (at 131.445 93.98 0)
      (effects (font (size 1.27 1.27) (thickness 0.15)) (justify left bottom) hide)
    )
    (property "Voltage" "50V" (id 9) (at 128.905 93.98 0)
      (effects (font (size 1.27 1.27)) (justify left bottom) hide)
    )
    (property "Dielectric" "X5R" (id 10) (at 126.365 93.98 0)
      (effects (font (size 1.27 1.27)) (justify left bottom) hide)
    )
    (pin "1")
    (pin "2")
  )

  (symbol (lib_id "sa800u-baseboard-hw:R_10k_0402") (at 272.415 79.248 270) (unit 1)
    (in_bom yes) (on_board yes) (fields_autoplaced)
    (property "Reference" "R41" (id 0) (at 274.32 80.518 90)
      (effects (font (size 1.524 1.524)) (justify left))
    )
    (property "Value" "R_10k_0402" (id 1) (at 268.605 79.248 0)
      (effects (font (size 1.524 1.524)) hide)
    )
    (property "Footprint" "sa800u-baseboard-hw-footprints:R_0402_1005Metric" (id 2) (at 277.495 84.328 0)
      (effects (font (size 1.524 1.524)) (justify left) hide)
    )
    (property "Datasheet" "https://www.bourns.com/docs/product-datasheets/cr.pdf" (id 3) (at 272.415 79.248 0)
      (effects (font (size 1.27 1.27)) hide)
    )
    (property "Manufacturer" "Bourns" (id 4) (at 282.575 84.328 0)
      (effects (font (size 1.524 1.524)) (justify left) hide)
    )
    (property "MPN" "CR0402-FX-1002GLF" (id 5) (at 280.035 84.328 0)
      (effects (font (size 1.524 1.524)) (justify left) hide)
    )
    (property "Val" "10k" (id 6) (at 274.32 83.6929 90)
      (effects (font (size 1.27 1.27)) (justify left))
    )
    (property "License" "Apache-2.0" (id 7) (at 247.015 99.568 0)
      (effects (font (size 1.27 1.27) (thickness 0.15)) (justify left bottom) hide)
    )
    (property "Author" "Antmicro" (id 8) (at 244.475 99.568 0)
      (effects (font (size 1.27 1.27) (thickness 0.15)) (justify left bottom) hide)
    )
    (property "Tolerance" "1%" (id 9) (at 262.255 99.568 0)
      (effects (font (size 1.27 1.27)) (justify left bottom) hide)
    )
    (pin "1")
    (pin "2")
  )

  (symbol (lib_id "sa800u-baseboard-hw:GND") (at 272.415 93.98 0) (unit 1)
    (in_bom yes) (on_board yes) (fields_autoplaced)
    (property "Reference" "#PWR031" (id 0) (at 272.415 100.33 0)
      (effects (font (size 1.27 1.27)) hide)
    )
    (property "Value" "GND" (id 1) (at 272.415 98.425 0))
    (property "Footprint" "" (id 2) (at 272.415 93.98 0)
      (effects (font (size 1.27 1.27)) hide)
    )
    (property "Datasheet" "" (id 3) (at 272.415 93.98 0)
      (effects (font (size 1.27 1.27)) hide)
    )
    (property "Author" "Antmicro" (id 4) (at 281.305 101.6 0)
      (effects (font (size 1.27 1.27) (thickness 0.15)) (justify left bottom) hide)
    )
    (property "License" "Apache-2.0" (id 5) (at 281.305 104.14 0)
      (effects (font (size 1.27 1.27) (thickness 0.15)) (justify left bottom) hide)
    )
    (pin "1")
  )

  (symbol (lib_id "sa800u-baseboard-hw:1N4148WS") (at 226.695 237.236 90) (mirror x) (unit 1)
    (in_bom yes) (on_board yes) (fields_autoplaced)
    (property "Reference" "D1" (id 0) (at 229.87 239.776 90)
      (effects (font (size 1.524 1.524)) (justify right))
    )
    (property "Value" "1N4148WS" (id 1) (at 229.87 243.586 90)
      (effects (font (size 1.524 1.524)) (justify right))
    )
    (property "Footprint" "sa800u-baseboard-hw-footprints:D_SOD-323F" (id 2) (at 221.615 242.316 0)
      (effects (font (size 1.524 1.524)) (justify left) hide)
    )
    (property "Datasheet" "https://www.onsemi.com/pub/Collateral/1N914BWS-D.pdf" (id 3) (at 219.075 242.316 0)
      (effects (font (size 1.524 1.524)) (justify left) hide)
    )
    (property "MPN" "1N4148WS" (id 4) (at 213.995 242.316 0)
      (effects (font (size 1.524 1.524)) (justify left) hide)
    )
    (property "Manufacturer" "ON Semiconductor" (id 5) (at 198.755 242.316 0)
      (effects (font (size 1.524 1.524)) (justify left) hide)
    )
    (property "Author" "Antmicro" (id 6) (at 247.015 258.826 0)
      (effects (font (size 1.27 1.27) (thickness 0.15)) (justify left bottom) hide)
    )
    (property "License" "Apache-2.0" (id 7) (at 249.555 258.826 0)
      (effects (font (size 1.27 1.27) (thickness 0.15)) (justify left bottom) hide)
    )
    (pin "A")
    (pin "K")
  )

  (symbol (lib_id "sa800u-baseboard-hw:TP_0.75mm_SMD") (at 269.24 242.57 270) (unit 1)
    (in_bom yes) (on_board yes) (fields_autoplaced)
    (property "Reference" "TP23" (id 0) (at 266.7 245.7449 90)
      (effects (font (size 1.27 1.27)) (justify right))
    )
    (property "Value" "TP_0.75mm_SMD" (id 1) (at 266.7 242.57 0)
      (effects (font (size 1.27 1.27)) hide)
    )
    (property "Footprint" "sa800u-baseboard-hw-footprints:TP_SMD_0.75mm" (id 2) (at 274.32 247.65 0)
      (effects (font (size 1.524 1.524)) (justify left) hide)
    )
    (property "Datasheet" "" (id 3) (at 276.86 247.65 0)
      (effects (font (size 1.524 1.524)) (justify left) hide)
    )
    (property "MPN" "" (id 4) (at 254 260.35 0)
      (effects (font (size 1.27 1.27) (thickness 0.15)) (justify left bottom) hide)
    )
    (property "Manufacturer" "" (id 5) (at 251.46 260.35 0)
      (effects (font (size 1.27 1.27) (thickness 0.15)) (justify left bottom) hide)
    )
    (property "Author" "Antmicro" (id 6) (at 248.92 260.35 0)
      (effects (font (size 1.27 1.27) (thickness 0.15)) (justify left bottom) hide)
    )
    (property "License" "Apache-2.0" (id 7) (at 246.38 260.35 0)
      (effects (font (size 1.27 1.27) (thickness 0.15)) (justify left bottom) hide)
    )
    (pin "1")
  )

  (symbol (lib_id "sa800u-baseboard-hw:TP_0.75mm_SMD") (at 271.78 242.57 270) (unit 1)
    (in_bom yes) (on_board yes) (fields_autoplaced)
    (property "Reference" "TP24" (id 0) (at 273.177 245.7449 90)
      (effects (font (size 1.27 1.27)) (justify left))
    )
    (property "Value" "TP_0.75mm_SMD" (id 1) (at 269.24 242.57 0)
      (effects (font (size 1.27 1.27)) hide)
    )
    (property "Footprint" "sa800u-baseboard-hw-footprints:TP_SMD_0.75mm" (id 2) (at 276.86 247.65 0)
      (effects (font (size 1.524 1.524)) (justify left) hide)
    )
    (property "Datasheet" "" (id 3) (at 279.4 247.65 0)
      (effects (font (size 1.524 1.524)) (justify left) hide)
    )
    (property "MPN" "" (id 4) (at 256.54 260.35 0)
      (effects (font (size 1.27 1.27) (thickness 0.15)) (justify left bottom) hide)
    )
    (property "Manufacturer" "" (id 5) (at 254 260.35 0)
      (effects (font (size 1.27 1.27) (thickness 0.15)) (justify left bottom) hide)
    )
    (property "Author" "Antmicro" (id 6) (at 251.46 260.35 0)
      (effects (font (size 1.27 1.27) (thickness 0.15)) (justify left bottom) hide)
    )
    (property "License" "Apache-2.0" (id 7) (at 248.92 260.35 0)
      (effects (font (size 1.27 1.27) (thickness 0.15)) (justify left bottom) hide)
    )
    (pin "1")
  )

  (symbol (lib_id "sa800u-baseboard-hw:GND") (at 281.94 104.14 0) (unit 1)
    (in_bom yes) (on_board yes) (fields_autoplaced)
    (property "Reference" "#PWR032" (id 0) (at 281.94 110.49 0)
      (effects (font (size 1.27 1.27)) hide)
    )
    (property "Value" "GND" (id 1) (at 281.94 108.585 0))
    (property "Footprint" "" (id 2) (at 281.94 104.14 0)
      (effects (font (size 1.27 1.27)) hide)
    )
    (property "Datasheet" "" (id 3) (at 281.94 104.14 0)
      (effects (font (size 1.27 1.27)) hide)
    )
    (property "Author" "Antmicro" (id 4) (at 290.83 111.76 0)
      (effects (font (size 1.27 1.27) (thickness 0.15)) (justify left bottom) hide)
    )
    (property "License" "Apache-2.0" (id 5) (at 290.83 114.3 0)
      (effects (font (size 1.27 1.27) (thickness 0.15)) (justify left bottom) hide)
    )
    (pin "1")
  )

  (symbol (lib_id "sa800u-baseboard-hw:R_20k_0402") (at 280.035 79.248 270) (unit 1)
    (in_bom yes) (on_board yes) (fields_autoplaced)
    (property "Reference" "R43" (id 0) (at 281.94 80.518 90)
      (effects (font (size 1.524 1.524)) (justify left))
    )
    (property "Value" "R_20k_0402" (id 1) (at 276.225 79.248 0)
      (effects (font (size 1.524 1.524)) hide)
    )
    (property "Footprint" "sa800u-baseboard-hw-footprints:R_0402_1005Metric" (id 2) (at 285.115 84.328 0)
      (effects (font (size 1.524 1.524)) (justify left) hide)
    )
    (property "Datasheet" "https://www.bourns.com/docs/product-datasheets/cr.pdf" (id 3) (at 280.035 79.248 0)
      (effects (font (size 1.27 1.27)) hide)
    )
    (property "Manufacturer" "Bourns" (id 4) (at 290.195 84.328 0)
      (effects (font (size 1.524 1.524)) (justify left) hide)
    )
    (property "MPN" "CR0402-FX-2002GLF" (id 5) (at 287.655 84.328 0)
      (effects (font (size 1.524 1.524)) (justify left) hide)
    )
    (property "Val" "20k" (id 6) (at 281.94 83.6929 90)
      (effects (font (size 1.27 1.27)) (justify left))
    )
    (property "License" "Apache-2.0" (id 7) (at 254.635 99.568 0)
      (effects (font (size 1.27 1.27) (thickness 0.15)) (justify left bottom) hide)
    )
    (property "Author" "Antmicro" (id 8) (at 252.095 99.568 0)
      (effects (font (size 1.27 1.27) (thickness 0.15)) (justify left bottom) hide)
    )
    (property "Tolerance" "1%" (id 9) (at 269.875 99.568 0)
      (effects (font (size 1.27 1.27)) (justify left bottom) hide)
    )
    (pin "1")
    (pin "2")
  )

  (symbol (lib_id "sa800u-baseboard-hw:BSS138PW") (at 334.645 212.09 0) (unit 1)
    (in_bom yes) (on_board yes) (fields_autoplaced)
    (property "Reference" "Q4" (id 0) (at 345.44 208.28 0)
      (effects (font (size 1.524 1.524)) (justify left))
    )
    (property "Value" "BSS138PW" (id 1) (at 345.44 212.09 0)
      (effects (font (size 1.524 1.524)) (justify left))
    )
    (property "Footprint" "sa800u-baseboard-hw-footprints:SC70-3" (id 2) (at 339.725 207.01 0)
      (effects (font (size 1.524 1.524)) (justify left) hide)
    )
    (property "Datasheet" "https://assets.nexperia.com/documents/data-sheet/BSS138PW.pdf" (id 3) (at 339.725 204.47 0)
      (effects (font (size 1.524 1.524)) (justify left) hide)
    )
    (property "MPN" "BSS138PW" (id 4) (at 339.725 199.39 0)
      (effects (font (size 1.524 1.524)) (justify left) hide)
    )
    (property "Manufacturer" "Nexperia" (id 5) (at 339.725 184.15 0)
      (effects (font (size 1.524 1.524)) (justify left) hide)
    )
    (property "Author" "Antmicro" (id 6) (at 357.505 233.68 0)
      (effects (font (size 1.27 1.27) (thickness 0.15)) (justify left bottom) hide)
    )
    (property "License" "Apache-2.0" (id 7) (at 357.505 236.22 0)
      (effects (font (size 1.27 1.27) (thickness 0.15)) (justify left bottom) hide)
    )
    (pin "1")
    (pin "2")
    (pin "3")
  )

  (symbol (lib_id "sa800u-baseboard-hw:TP_0.75mm_SMD") (at 318.77 242.57 90) (mirror x) (unit 1)
    (in_bom yes) (on_board yes) (fields_autoplaced)
    (property "Reference" "TP26" (id 0) (at 320.929 245.7449 90)
      (effects (font (size 1.27 1.27)) (justify right))
    )
    (property "Value" "TP_0.75mm_SMD" (id 1) (at 321.31 242.57 0)
      (effects (font (size 1.27 1.27)) hide)
    )
    (property "Footprint" "sa800u-baseboard-hw-footprints:TP_SMD_0.75mm" (id 2) (at 313.69 247.65 0)
      (effects (font (size 1.524 1.524)) (justify left) hide)
    )
    (property "Datasheet" "" (id 3) (at 311.15 247.65 0)
      (effects (font (size 1.524 1.524)) (justify left) hide)
    )
    (property "MPN" "" (id 4) (at 334.01 260.35 0)
      (effects (font (size 1.27 1.27) (thickness 0.15)) (justify left bottom) hide)
    )
    (property "Manufacturer" "" (id 5) (at 336.55 260.35 0)
      (effects (font (size 1.27 1.27) (thickness 0.15)) (justify left bottom) hide)
    )
    (property "Author" "Antmicro" (id 6) (at 339.09 260.35 0)
      (effects (font (size 1.27 1.27) (thickness 0.15)) (justify left bottom) hide)
    )
    (property "License" "Apache-2.0" (id 7) (at 341.63 260.35 0)
      (effects (font (size 1.27 1.27) (thickness 0.15)) (justify left bottom) hide)
    )
    (pin "1")
  )

  (symbol (lib_id "sa800u-baseboard-hw:TP_0.75mm_SMD") (at 316.23 242.57 90) (mirror x) (unit 1)
    (in_bom yes) (on_board yes) (fields_autoplaced)
    (property "Reference" "TP25" (id 0) (at 314.452 245.7449 90)
      (effects (font (size 1.27 1.27)) (justify left))
    )
    (property "Value" "TP_0.75mm_SMD" (id 1) (at 318.77 242.57 0)
      (effects (font (size 1.27 1.27)) hide)
    )
    (property "Footprint" "sa800u-baseboard-hw-footprints:TP_SMD_0.75mm" (id 2) (at 311.15 247.65 0)
      (effects (font (size 1.524 1.524)) (justify left) hide)
    )
    (property "Datasheet" "" (id 3) (at 308.61 247.65 0)
      (effects (font (size 1.524 1.524)) (justify left) hide)
    )
    (property "MPN" "" (id 4) (at 331.47 260.35 0)
      (effects (font (size 1.27 1.27) (thickness 0.15)) (justify left bottom) hide)
    )
    (property "Manufacturer" "" (id 5) (at 334.01 260.35 0)
      (effects (font (size 1.27 1.27) (thickness 0.15)) (justify left bottom) hide)
    )
    (property "Author" "Antmicro" (id 6) (at 336.55 260.35 0)
      (effects (font (size 1.27 1.27) (thickness 0.15)) (justify left bottom) hide)
    )
    (property "License" "Apache-2.0" (id 7) (at 339.09 260.35 0)
      (effects (font (size 1.27 1.27) (thickness 0.15)) (justify left bottom) hide)
    )
    (pin "1")
  )

  (symbol (lib_id "sa800u-baseboard-hw:R_10k_0402") (at 43.18 111.125 270) (unit 1)
    (in_bom yes) (on_board yes) (fields_autoplaced)
    (property "Reference" "R17" (id 0) (at 45.72 112.395 90)
      (effects (font (size 1.524 1.524)) (justify left))
    )
    (property "Value" "R_10k_0402" (id 1) (at 39.37 111.125 0)
      (effects (font (size 1.524 1.524)) hide)
    )
    (property "Footprint" "sa800u-baseboard-hw-footprints:R_0402_1005Metric" (id 2) (at 48.26 116.205 0)
      (effects (font (size 1.524 1.524)) (justify left) hide)
    )
    (property "Datasheet" "https://www.bourns.com/docs/product-datasheets/cr.pdf" (id 3) (at 43.18 111.125 0)
      (effects (font (size 1.27 1.27)) hide)
    )
    (property "Manufacturer" "Bourns" (id 4) (at 53.34 116.205 0)
      (effects (font (size 1.524 1.524)) (justify left) hide)
    )
    (property "MPN" "CR0402-FX-1002GLF" (id 5) (at 50.8 116.205 0)
      (effects (font (size 1.524 1.524)) (justify left) hide)
    )
    (property "Val" "10k" (id 6) (at 45.72 115.5699 90)
      (effects (font (size 1.27 1.27)) (justify left))
    )
    (property "License" "Apache-2.0" (id 7) (at 17.78 131.445 0)
      (effects (font (size 1.27 1.27) (thickness 0.15)) (justify left bottom) hide)
    )
    (property "Author" "Antmicro" (id 8) (at 15.24 131.445 0)
      (effects (font (size 1.27 1.27) (thickness 0.15)) (justify left bottom) hide)
    )
    (property "Tolerance" "1%" (id 9) (at 33.02 131.445 0)
      (effects (font (size 1.27 1.27)) (justify left bottom) hide)
    )
    (pin "1")
    (pin "2")
  )

  (symbol (lib_id "sa800u-baseboard-hw:TP_0.75mm_SMD") (at 396.24 243.459 90) (unit 1)
    (in_bom yes) (on_board yes) (fields_autoplaced)
    (property "Reference" "TP27" (id 0) (at 397.891 240.2839 90)
      (effects (font (size 1.27 1.27)) (justify right))
    )
    (property "Value" "TP_0.75mm_SMD" (id 1) (at 396.24 243.459 0)
      (effects (font (size 1.27 1.27)) hide)
    )
    (property "Footprint" "sa800u-baseboard-hw-footprints:TP_SMD_0.75mm" (id 2) (at 396.24 243.459 0)
      (effects (font (size 1.27 1.27)) hide)
    )
    (property "Datasheet" "" (id 3) (at 396.24 243.459 0)
      (effects (font (size 1.27 1.27)) hide)
    )
    (property "MPN" "" (id 4) (at 411.48 225.679 0)
      (effects (font (size 1.27 1.27) (thickness 0.15)) (justify left bottom) hide)
    )
    (property "Manufacturer" "" (id 5) (at 414.02 225.679 0)
      (effects (font (size 1.27 1.27) (thickness 0.15)) (justify left bottom) hide)
    )
    (property "Author" "Antmicro" (id 6) (at 416.56 225.679 0)
      (effects (font (size 1.27 1.27) (thickness 0.15)) (justify left bottom) hide)
    )
    (property "License" "Apache-2.0" (id 7) (at 419.1 225.679 0)
      (effects (font (size 1.27 1.27) (thickness 0.15)) (justify left bottom) hide)
    )
    (pin "1")
  )

  (symbol (lib_id "sa800u-baseboard-hw:GND") (at 396.24 243.459 0) (unit 1)
    (in_bom yes) (on_board yes) (fields_autoplaced)
    (property "Reference" "#PWR039" (id 0) (at 396.24 249.809 0)
      (effects (font (size 1.27 1.27)) hide)
    )
    (property "Value" "GND" (id 1) (at 396.24 248.539 0))
    (property "Footprint" "" (id 2) (at 396.24 243.459 0)
      (effects (font (size 1.27 1.27)) hide)
    )
    (property "Datasheet" "" (id 3) (at 396.24 243.459 0)
      (effects (font (size 1.27 1.27)) hide)
    )
    (property "Author" "Antmicro" (id 4) (at 405.13 251.079 0)
      (effects (font (size 1.27 1.27) (thickness 0.15)) (justify left bottom) hide)
    )
    (property "License" "Apache-2.0" (id 5) (at 405.13 253.619 0)
      (effects (font (size 1.27 1.27) (thickness 0.15)) (justify left bottom) hide)
    )
    (pin "1")
  )

  (symbol (lib_id "sa800u-baseboard-hw:GND") (at 134.62 243.84 0) (unit 1)
    (in_bom yes) (on_board yes) (fields_autoplaced)
    (property "Reference" "#PWR017" (id 0) (at 134.62 250.19 0)
      (effects (font (size 1.27 1.27)) hide)
    )
    (property "Value" "GND" (id 1) (at 134.62 248.92 0))
    (property "Footprint" "" (id 2) (at 134.62 243.84 0)
      (effects (font (size 1.27 1.27)) hide)
    )
    (property "Datasheet" "" (id 3) (at 134.62 243.84 0)
      (effects (font (size 1.27 1.27)) hide)
    )
    (property "Author" "Antmicro" (id 4) (at 143.51 251.46 0)
      (effects (font (size 1.27 1.27) (thickness 0.15)) (justify left bottom) hide)
    )
    (property "License" "Apache-2.0" (id 5) (at 143.51 254 0)
      (effects (font (size 1.27 1.27) (thickness 0.15)) (justify left bottom) hide)
    )
    (pin "1")
  )

  (symbol (lib_id "sa800u-baseboard-hw:GND") (at 129.54 243.84 0) (unit 1)
    (in_bom yes) (on_board yes) (fields_autoplaced)
    (property "Reference" "#PWR015" (id 0) (at 129.54 250.19 0)
      (effects (font (size 1.27 1.27)) hide)
    )
    (property "Value" "GND" (id 1) (at 129.54 248.92 0))
    (property "Footprint" "" (id 2) (at 129.54 243.84 0)
      (effects (font (size 1.27 1.27)) hide)
    )
    (property "Datasheet" "" (id 3) (at 129.54 243.84 0)
      (effects (font (size 1.27 1.27)) hide)
    )
    (property "Author" "Antmicro" (id 4) (at 138.43 251.46 0)
      (effects (font (size 1.27 1.27) (thickness 0.15)) (justify left bottom) hide)
    )
    (property "License" "Apache-2.0" (id 5) (at 138.43 254 0)
      (effects (font (size 1.27 1.27) (thickness 0.15)) (justify left bottom) hide)
    )
    (pin "1")
  )

  (symbol (lib_id "sa800u-baseboard-hw:NTS0102_XSON") (at 283.845 234.95 0) (unit 1)
    (in_bom yes) (on_board yes) (fields_autoplaced)
    (property "Reference" "U4" (id 0) (at 294.005 227.33 0))
    (property "Value" "NTS0102_XSON" (id 1) (at 294.005 250.19 0)
      (effects (font (size 1.27 1.27)) hide)
    )
    (property "Footprint" "sa800u-baseboard-hw-footprints:XSON-8_1x1.95mm_P0.5mm" (id 2) (at 281.305 222.25 0)
      (effects (font (size 1.27 1.27)) hide)
    )
    (property "Datasheet" "http://www.farnell.com/datasheets/1760723.pdf" (id 3) (at 300.355 215.9 0)
      (effects (font (size 1.27 1.27)) hide)
    )
    (property "MPN" "NTS0102GT" (id 4) (at 294.005 229.87 0))
    (property "Manufacturer" "NXP" (id 5) (at 283.845 224.1804 0)
      (effects (font (size 1.27 1.27)) hide)
    )
    (property "Author" "Antmicro" (id 6) (at 319.405 252.73 0)
      (effects (font (size 1.27 1.27) (thickness 0.15)) (justify left bottom) hide)
    )
    (property "License" "Apache-2.0" (id 7) (at 319.405 255.27 0)
      (effects (font (size 1.27 1.27) (thickness 0.15)) (justify left bottom) hide)
    )
    (pin "1")
    (pin "2")
    (pin "3")
    (pin "4")
    (pin "5")
    (pin "6")
    (pin "7")
    (pin "8")
  )

  (symbol (lib_id "sa800u-baseboard-hw:C_100n_0402") (at 248.285 228.6 270) (unit 1)
    (in_bom yes) (on_board yes) (fields_autoplaced)
    (property "Reference" "C44" (id 0) (at 251.079 229.8763 90)
      (effects (font (size 1.524 1.524)) (justify left))
    )
    (property "Value" "C_100n_0402" (id 1) (at 244.475 228.6 0)
      (effects (font (size 1.524 1.524)) hide)
    )
    (property "Footprint" "sa800u-baseboard-hw-footprints:C_0402_1005Metric" (id 2) (at 253.365 233.68 0)
      (effects (font (size 1.524 1.524)) (justify left) hide)
    )
    (property "Datasheet" "https://search.murata.co.jp/Ceramy/image/img/A01X/G101/ENG/GRM155R61H104KE14-01.pdf" (id 3) (at 248.285 228.6 0)
      (effects (font (size 1.27 1.27)) hide)
    )
    (property "Manufacturer" "Murata" (id 4) (at 258.445 233.68 0)
      (effects (font (size 1.524 1.524)) (justify left) hide)
    )
    (property "MPN" "GRM155R61H104KE14D" (id 5) (at 255.905 233.68 0)
      (effects (font (size 1.524 1.524)) (justify left) hide)
    )
    (property "Val" "100n" (id 6) (at 251.079 233.0512 90)
      (effects (font (size 1.27 1.27)) (justify left))
    )
    (property "License" "Apache-2.0" (id 7) (at 225.425 248.92 0)
      (effects (font (size 1.27 1.27) (thickness 0.15)) (justify left bottom) hide)
    )
    (property "Author" "Antmicro" (id 8) (at 222.885 248.92 0)
      (effects (font (size 1.27 1.27) (thickness 0.15)) (justify left bottom) hide)
    )
    (property "Voltage" "50V" (id 9) (at 220.345 248.92 0)
      (effects (font (size 1.27 1.27)) (justify left bottom) hide)
    )
    (property "Dielectric" "X5R" (id 10) (at 217.805 248.92 0)
      (effects (font (size 1.27 1.27)) (justify left bottom) hide)
    )
    (pin "1")
    (pin "2")
  )

  (symbol (lib_id "sa800u-baseboard-hw:GND") (at 248.285 233.68 0) (unit 1)
    (in_bom yes) (on_board yes) (fields_autoplaced)
    (property "Reference" "#PWR028" (id 0) (at 248.285 240.03 0)
      (effects (font (size 1.27 1.27)) hide)
    )
    (property "Value" "GND" (id 1) (at 248.285 238.76 0))
    (property "Footprint" "" (id 2) (at 248.285 233.68 0)
      (effects (font (size 1.27 1.27)) hide)
    )
    (property "Datasheet" "" (id 3) (at 248.285 233.68 0)
      (effects (font (size 1.27 1.27)) hide)
    )
    (property "Author" "Antmicro" (id 4) (at 257.175 241.3 0)
      (effects (font (size 1.27 1.27) (thickness 0.15)) (justify left bottom) hide)
    )
    (property "License" "Apache-2.0" (id 5) (at 257.175 243.84 0)
      (effects (font (size 1.27 1.27) (thickness 0.15)) (justify left bottom) hide)
    )
    (pin "1")
  )

  (symbol (lib_id "sa800u-baseboard-hw:R_2k_0402") (at 271.78 235.077 90) (unit 1)
    (in_bom yes) (on_board yes) (fields_autoplaced)
    (property "Reference" "R36" (id 0) (at 274.32 231.267 90)
      (effects (font (size 1.524 1.524)) (justify right))
    )
    (property "Value" "R_2k_0402" (id 1) (at 275.59 235.077 0)
      (effects (font (size 1.524 1.524)) hide)
    )
    (property "Footprint" "sa800u-baseboard-hw-footprints:R_0402_1005Metric" (id 2) (at 266.7 229.997 0)
      (effects (font (size 1.524 1.524)) (justify left) hide)
    )
    (property "Datasheet" "https://www.bourns.com/docs/product-datasheets/cr.pdf" (id 3) (at 271.78 235.077 0)
      (effects (font (size 1.27 1.27)) hide)
    )
    (property "Manufacturer" "Bourns" (id 4) (at 261.62 229.997 0)
      (effects (font (size 1.524 1.524)) (justify left) hide)
    )
    (property "MPN" "CR0402-FX-2001GLF" (id 5) (at 264.16 229.997 0)
      (effects (font (size 1.524 1.524)) (justify left) hide)
    )
    (property "Val" "2k" (id 6) (at 274.32 234.4419 90)
      (effects (font (size 1.27 1.27)) (justify right))
    )
    (property "License" "Apache-2.0" (id 7) (at 297.18 214.757 0)
      (effects (font (size 1.27 1.27) (thickness 0.15)) (justify left bottom) hide)
    )
    (property "Author" "Antmicro" (id 8) (at 299.72 214.757 0)
      (effects (font (size 1.27 1.27) (thickness 0.15)) (justify left bottom) hide)
    )
    (property "Tolerance" "1%" (id 9) (at 281.94 214.757 0)
      (effects (font (size 1.27 1.27)) (justify left bottom) hide)
    )
    (pin "1")
    (pin "2")
  )

  (symbol (lib_id "sa800u-baseboard-hw:C_100n_0402") (at 339.725 228.6 90) (mirror x) (unit 1)
    (in_bom yes) (on_board yes) (fields_autoplaced)
    (property "Reference" "C54" (id 0) (at 342.9 229.8763 90)
      (effects (font (size 1.524 1.524)) (justify right))
    )
    (property "Value" "C_100n_0402" (id 1) (at 343.535 228.6 0)
      (effects (font (size 1.524 1.524)) hide)
    )
    (property "Footprint" "sa800u-baseboard-hw-footprints:C_0402_1005Metric" (id 2) (at 334.645 233.68 0)
      (effects (font (size 1.524 1.524)) (justify left) hide)
    )
    (property "Datasheet" "https://search.murata.co.jp/Ceramy/image/img/A01X/G101/ENG/GRM155R61H104KE14-01.pdf" (id 3) (at 339.725 228.6 0)
      (effects (font (size 1.27 1.27)) hide)
    )
    (property "Manufacturer" "Murata" (id 4) (at 329.565 233.68 0)
      (effects (font (size 1.524 1.524)) (justify left) hide)
    )
    (property "MPN" "GRM155R61H104KE14D" (id 5) (at 332.105 233.68 0)
      (effects (font (size 1.524 1.524)) (justify left) hide)
    )
    (property "Val" "100n" (id 6) (at 342.9 233.0512 90)
      (effects (font (size 1.27 1.27)) (justify right))
    )
    (property "License" "Apache-2.0" (id 7) (at 362.585 248.92 0)
      (effects (font (size 1.27 1.27) (thickness 0.15)) (justify left bottom) hide)
    )
    (property "Author" "Antmicro" (id 8) (at 365.125 248.92 0)
      (effects (font (size 1.27 1.27) (thickness 0.15)) (justify left bottom) hide)
    )
    (property "Voltage" "50V" (id 9) (at 367.665 248.92 0)
      (effects (font (size 1.27 1.27)) (justify left bottom) hide)
    )
    (property "Dielectric" "X5R" (id 10) (at 370.205 248.92 0)
      (effects (font (size 1.27 1.27)) (justify left bottom) hide)
    )
    (pin "1")
    (pin "2")
  )

  (symbol (lib_id "sa800u-baseboard-hw:GND") (at 339.725 233.68 0) (mirror y) (unit 1)
    (in_bom yes) (on_board yes) (fields_autoplaced)
    (property "Reference" "#PWR033" (id 0) (at 339.725 240.03 0)
      (effects (font (size 1.27 1.27)) hide)
    )
    (property "Value" "GND" (id 1) (at 339.725 238.76 0))
    (property "Footprint" "" (id 2) (at 339.725 233.68 0)
      (effects (font (size 1.27 1.27)) hide)
    )
    (property "Datasheet" "" (id 3) (at 339.725 233.68 0)
      (effects (font (size 1.27 1.27)) hide)
    )
    (property "Author" "Antmicro" (id 4) (at 330.835 241.3 0)
      (effects (font (size 1.27 1.27) (thickness 0.15)) (justify left bottom) hide)
    )
    (property "License" "Apache-2.0" (id 5) (at 330.835 243.84 0)
      (effects (font (size 1.27 1.27) (thickness 0.15)) (justify left bottom) hide)
    )
    (pin "1")
  )

  (symbol (lib_id "sa800u-baseboard-hw:GND") (at 305.435 243.84 0) (mirror y) (unit 1)
    (in_bom yes) (on_board yes) (fields_autoplaced)
    (property "Reference" "#PWR030" (id 0) (at 305.435 250.19 0)
      (effects (font (size 1.27 1.27)) hide)
    )
    (property "Value" "GND" (id 1) (at 305.435 248.92 0))
    (property "Footprint" "" (id 2) (at 305.435 243.84 0)
      (effects (font (size 1.27 1.27)) hide)
    )
    (property "Datasheet" "" (id 3) (at 305.435 243.84 0)
      (effects (font (size 1.27 1.27)) hide)
    )
    (property "Author" "Antmicro" (id 4) (at 296.545 251.46 0)
      (effects (font (size 1.27 1.27) (thickness 0.15)) (justify left bottom) hide)
    )
    (property "License" "Apache-2.0" (id 5) (at 296.545 254 0)
      (effects (font (size 1.27 1.27) (thickness 0.15)) (justify left bottom) hide)
    )
    (pin "1")
  )

  (symbol (lib_id "sa800u-baseboard-hw:R_2k_0402") (at 269.24 235.077 90) (unit 1)
    (in_bom yes) (on_board yes) (fields_autoplaced)
    (property "Reference" "R34" (id 0) (at 266.7 231.267 90)
      (effects (font (size 1.524 1.524)) (justify left))
    )
    (property "Value" "R_2k_0402" (id 1) (at 273.05 235.077 0)
      (effects (font (size 1.524 1.524)) hide)
    )
    (property "Footprint" "sa800u-baseboard-hw-footprints:R_0402_1005Metric" (id 2) (at 264.16 229.997 0)
      (effects (font (size 1.524 1.524)) (justify left) hide)
    )
    (property "Datasheet" "https://www.bourns.com/docs/product-datasheets/cr.pdf" (id 3) (at 269.24 235.077 0)
      (effects (font (size 1.27 1.27)) hide)
    )
    (property "Manufacturer" "Bourns" (id 4) (at 259.08 229.997 0)
      (effects (font (size 1.524 1.524)) (justify left) hide)
    )
    (property "MPN" "CR0402-FX-2001GLF" (id 5) (at 261.62 229.997 0)
      (effects (font (size 1.524 1.524)) (justify left) hide)
    )
    (property "Val" "2k" (id 6) (at 266.7 234.4419 90)
      (effects (font (size 1.27 1.27)) (justify left))
    )
    (property "License" "Apache-2.0" (id 7) (at 294.64 214.757 0)
      (effects (font (size 1.27 1.27) (thickness 0.15)) (justify left bottom) hide)
    )
    (property "Author" "Antmicro" (id 8) (at 297.18 214.757 0)
      (effects (font (size 1.27 1.27) (thickness 0.15)) (justify left bottom) hide)
    )
    (property "Tolerance" "1%" (id 9) (at 279.4 214.757 0)
      (effects (font (size 1.27 1.27)) (justify left bottom) hide)
    )
    (pin "1")
    (pin "2")
  )

  (symbol (lib_id "sa800u-baseboard-hw:R_2k_0402") (at 316.23 234.696 270) (mirror x) (unit 1)
    (in_bom yes) (on_board yes) (fields_autoplaced)
    (property "Reference" "R44" (id 0) (at 313.69 230.886 90)
      (effects (font (size 1.524 1.524)) (justify right))
    )
    (property "Value" "R_2k_0402" (id 1) (at 312.42 234.696 0)
      (effects (font (size 1.524 1.524)) hide)
    )
    (property "Footprint" "sa800u-baseboard-hw-footprints:R_0402_1005Metric" (id 2) (at 321.31 229.616 0)
      (effects (font (size 1.524 1.524)) (justify left) hide)
    )
    (property "Datasheet" "https://www.bourns.com/docs/product-datasheets/cr.pdf" (id 3) (at 316.23 234.696 0)
      (effects (font (size 1.27 1.27)) hide)
    )
    (property "Manufacturer" "Bourns" (id 4) (at 326.39 229.616 0)
      (effects (font (size 1.524 1.524)) (justify left) hide)
    )
    (property "MPN" "CR0402-FX-2001GLF" (id 5) (at 323.85 229.616 0)
      (effects (font (size 1.524 1.524)) (justify left) hide)
    )
    (property "Val" "2k" (id 6) (at 313.69 234.0609 90)
      (effects (font (size 1.27 1.27)) (justify right))
    )
    (property "License" "Apache-2.0" (id 7) (at 290.83 214.376 0)
      (effects (font (size 1.27 1.27) (thickness 0.15)) (justify left bottom) hide)
    )
    (property "Author" "Antmicro" (id 8) (at 288.29 214.376 0)
      (effects (font (size 1.27 1.27) (thickness 0.15)) (justify left bottom) hide)
    )
    (property "Tolerance" "1%" (id 9) (at 306.07 214.376 0)
      (effects (font (size 1.27 1.27)) (justify left bottom) hide)
    )
    (pin "1")
    (pin "2")
  )

  (symbol (lib_id "sa800u-baseboard-hw:R_2k_0402") (at 318.77 234.696 270) (mirror x) (unit 1)
    (in_bom yes) (on_board yes) (fields_autoplaced)
    (property "Reference" "R46" (id 0) (at 321.31 230.886 90)
      (effects (font (size 1.524 1.524)) (justify left))
    )
    (property "Value" "R_2k_0402" (id 1) (at 314.96 234.696 0)
      (effects (font (size 1.524 1.524)) hide)
    )
    (property "Footprint" "sa800u-baseboard-hw-footprints:R_0402_1005Metric" (id 2) (at 323.85 229.616 0)
      (effects (font (size 1.524 1.524)) (justify left) hide)
    )
    (property "Datasheet" "https://www.bourns.com/docs/product-datasheets/cr.pdf" (id 3) (at 318.77 234.696 0)
      (effects (font (size 1.27 1.27)) hide)
    )
    (property "Manufacturer" "Bourns" (id 4) (at 328.93 229.616 0)
      (effects (font (size 1.524 1.524)) (justify left) hide)
    )
    (property "MPN" "CR0402-FX-2001GLF" (id 5) (at 326.39 229.616 0)
      (effects (font (size 1.524 1.524)) (justify left) hide)
    )
    (property "Val" "2k" (id 6) (at 321.31 234.0609 90)
      (effects (font (size 1.27 1.27)) (justify left))
    )
    (property "License" "Apache-2.0" (id 7) (at 293.37 214.376 0)
      (effects (font (size 1.27 1.27) (thickness 0.15)) (justify left bottom) hide)
    )
    (property "Author" "Antmicro" (id 8) (at 290.83 214.376 0)
      (effects (font (size 1.27 1.27) (thickness 0.15)) (justify left bottom) hide)
    )
    (property "Tolerance" "1%" (id 9) (at 308.61 214.376 0)
      (effects (font (size 1.27 1.27)) (justify left bottom) hide)
    )
    (pin "1")
    (pin "2")
  )

  (symbol (lib_id "sa800u-baseboard-hw:BSS138PW") (at 172.085 238.76 270) (unit 1)
    (in_bom yes) (on_board yes)
    (property "Reference" "Q1" (id 0) (at 174.625 250.063 90)
      (effects (font (size 1.524 1.524)))
    )
    (property "Value" "BSS138PW" (id 1) (at 174.625 252.349 90)
      (effects (font (size 1.524 1.524)))
    )
    (property "Footprint" "sa800u-baseboard-hw-footprints:SC70-3" (id 2) (at 177.165 243.84 0)
      (effects (font (size 1.524 1.524)) (justify left) hide)
    )
    (property "Datasheet" "https://assets.nexperia.com/documents/data-sheet/BSS138PW.pdf" (id 3) (at 179.705 243.84 0)
      (effects (font (size 1.524 1.524)) (justify left) hide)
    )
    (property "MPN" "BSS138PW" (id 4) (at 184.785 243.84 0)
      (effects (font (size 1.524 1.524)) (justify left) hide)
    )
    (property "Manufacturer" "Nexperia" (id 5) (at 200.025 243.84 0)
      (effects (font (size 1.524 1.524)) (justify left) hide)
    )
    (property "Author" "Antmicro" (id 6) (at 150.495 261.62 0)
      (effects (font (size 1.27 1.27) (thickness 0.15)) (justify left bottom) hide)
    )
    (property "License" "Apache-2.0" (id 7) (at 147.955 261.62 0)
      (effects (font (size 1.27 1.27) (thickness 0.15)) (justify left bottom) hide)
    )
    (pin "1")
    (pin "2")
    (pin "3")
  )

  (symbol (lib_id "sa800u-baseboard-hw:BSS138PW") (at 172.085 259.715 270) (unit 1)
    (in_bom yes) (on_board yes)
    (property "Reference" "Q2" (id 0) (at 174.498 270.891 90)
      (effects (font (size 1.524 1.524)))
    )
    (property "Value" "BSS138PW" (id 1) (at 174.498 273.177 90)
      (effects (font (size 1.524 1.524)))
    )
    (property "Footprint" "sa800u-baseboard-hw-footprints:SC70-3" (id 2) (at 177.165 264.795 0)
      (effects (font (size 1.524 1.524)) (justify left) hide)
    )
    (property "Datasheet" "https://assets.nexperia.com/documents/data-sheet/BSS138PW.pdf" (id 3) (at 179.705 264.795 0)
      (effects (font (size 1.524 1.524)) (justify left) hide)
    )
    (property "MPN" "BSS138PW" (id 4) (at 184.785 264.795 0)
      (effects (font (size 1.524 1.524)) (justify left) hide)
    )
    (property "Manufacturer" "Nexperia" (id 5) (at 200.025 264.795 0)
      (effects (font (size 1.524 1.524)) (justify left) hide)
    )
    (property "Author" "Antmicro" (id 6) (at 150.495 282.575 0)
      (effects (font (size 1.27 1.27) (thickness 0.15)) (justify left bottom) hide)
    )
    (property "License" "Apache-2.0" (id 7) (at 147.955 282.575 0)
      (effects (font (size 1.27 1.27) (thickness 0.15)) (justify left bottom) hide)
    )
    (pin "1")
    (pin "2")
    (pin "3")
  )

  (symbol (lib_id "sa800u-baseboard-hw:BSS138PW") (at 216.535 249.555 270) (unit 1)
    (in_bom yes) (on_board yes)
    (property "Reference" "Q3" (id 0) (at 219.329 260.731 90)
      (effects (font (size 1.524 1.524)))
    )
    (property "Value" "BSS138PW" (id 1) (at 220.091 262.89 90)
      (effects (font (size 1.524 1.524)))
    )
    (property "Footprint" "sa800u-baseboard-hw-footprints:SC70-3" (id 2) (at 221.615 254.635 0)
      (effects (font (size 1.524 1.524)) (justify left) hide)
    )
    (property "Datasheet" "https://assets.nexperia.com/documents/data-sheet/BSS138PW.pdf" (id 3) (at 224.155 254.635 0)
      (effects (font (size 1.524 1.524)) (justify left) hide)
    )
    (property "MPN" "BSS138PW" (id 4) (at 229.235 254.635 0)
      (effects (font (size 1.524 1.524)) (justify left) hide)
    )
    (property "Manufacturer" "Nexperia" (id 5) (at 244.475 254.635 0)
      (effects (font (size 1.524 1.524)) (justify left) hide)
    )
    (property "Author" "Antmicro" (id 6) (at 194.945 272.415 0)
      (effects (font (size 1.27 1.27) (thickness 0.15)) (justify left bottom) hide)
    )
    (property "License" "Apache-2.0" (id 7) (at 192.405 272.415 0)
      (effects (font (size 1.27 1.27) (thickness 0.15)) (justify left bottom) hide)
    )
    (pin "1")
    (pin "2")
    (pin "3")
  )

  (symbol (lib_id "sa800u-baseboard-hw:GND") (at 403.352 75.946 0) (unit 1)
    (in_bom yes) (on_board yes) (fields_autoplaced)
    (property "Reference" "#PWR0101" (id 0) (at 403.352 82.296 0)
      (effects (font (size 1.27 1.27)) hide)
    )
    (property "Value" "GND" (id 1) (at 403.352 80.391 0))
    (property "Footprint" "" (id 2) (at 403.352 75.946 0)
      (effects (font (size 1.27 1.27)) hide)
    )
    (property "Datasheet" "" (id 3) (at 403.352 75.946 0)
      (effects (font (size 1.27 1.27)) hide)
    )
    (property "Author" "Antmicro" (id 4) (at 412.242 83.566 0)
      (effects (font (size 1.27 1.27) (thickness 0.15)) (justify left bottom) hide)
    )
    (property "License" "Apache-2.0" (id 5) (at 412.242 86.106 0)
      (effects (font (size 1.27 1.27) (thickness 0.15)) (justify left bottom) hide)
    )
    (pin "1")
  )

  (symbol (lib_id "sa800u-baseboard-hw:PWR_FLAG") (at 272.415 73.66 0) (unit 1)
    (in_bom yes) (on_board yes)
    (property "Reference" "#FLG0105" (id 0) (at 272.415 71.755 0)
      (effects (font (size 1.27 1.27)) hide)
    )
    (property "Value" "PWR_FLAG" (id 1) (at 272.415 70.104 0))
    (property "Footprint" "" (id 2) (at 272.415 73.66 0)
      (effects (font (size 1.27 1.27)) hide)
    )
    (property "Datasheet" "~" (id 3) (at 272.415 73.66 0)
      (effects (font (size 1.27 1.27)) hide)
    )
    (pin "1")
  )
)
